FILE_TYPE = MACRO_DRAWING;
SET COLOR_WIRE YELLOW;
SET COLOR_PROP MONO;
SET COLOR_DOT WHITE;
SET COLOR_ARC YELLOW;
SET COLOR_BODY GREEN;
SET COLOR_NOTE MONO;
SET PROP_DISPLAY VALUE;
SET PAGE_NUMBER P167;
FORCEADD TMP421..1
(-4000 4450);
FORCEPROP 2 LASTPIN (-4300 4300) $PN 4
J 2
(-4310 4310);
DISPLAY 0.617021 (-4310 4310);
PAINT ORANGE (-4310 4310);
FORCEPROP 2 LASTPIN (-4300 4350) $PN 3
J 2
(-4310 4360);
DISPLAY 0.617021 (-4310 4360);
PAINT ORANGE (-4310 4360);
FORCEPROP 2 LASTPIN (-4300 4450) $PN 2
J 2
(-4310 4460);
DISPLAY 0.617021 (-4310 4460);
PAINT ORANGE (-4310 4460);
FORCEPROP 2 LASTPIN (-4300 4500) $PN 1
J 2
(-4310 4510);
DISPLAY 0.617021 (-4310 4510);
PAINT ORANGE (-4310 4510);
FORCEPROP 2 LASTPIN (-4300 4600) $PN 8
J 2
(-4310 4610);
DISPLAY 0.617021 (-4310 4610);
PAINT ORANGE (-4310 4610);
FORCEPROP 1 LAST MATERIAL IC
J 0
(-4250 4800);
DISPLAY 0.617021 (-4250 4800);
PAINT SKYBLUE (-4250 4800);
FORCEPROP 1 LAST LOCATION U9B4
J 0
(-4250 4850);
DISPLAY 0.617021 (-4250 4850);
PAINT AQUA (-4250 4850);
FORCEPROP 1 LAST PART_NUMBER G62962-001
J 0
(-4250 4150);
DISPLAY 0.617021 (-4250 4150);
PAINT BLUE (-4250 4150);
FORCEPROP 2 LASTPIN (-3700 4500) $PN 6
J 0
(-3690 4510);
DISPLAY 0.617021 (-3690 4510);
PAINT ORANGE (-3690 4510);
FORCEPROP 2 LASTPIN (-3700 4250) $PN 5
J 0
(-3690 4260);
DISPLAY 0.617021 (-3690 4260);
PAINT ORANGE (-3690 4260);
FORCEPROP 2 LASTPIN (-3700 4450) $PN 7
J 0
(-3690 4460);
DISPLAY 0.617021 (-3690 4460);
PAINT ORANGE (-3690 4460);
FORCEPROP 2 LAST ROOM TEMP_SENSORS
J 0
(-4250 4900);
DISPLAY 1.021277 (-4250 4900);
PAINT ORANGE (-4250 4900);
DISPLAY INVISIBLE (-4250 4900);
FORCEPROP 2 LAST CDS_LOCATION U9B4
J 0
(-4250 4850);
DISPLAY 0.617021 (-4250 4850);
PAINT AQUA (-4250 4850);
DISPLAY INVISIBLE (-4250 4850);
FORCEPROP 2 LAST SEC 1
J 0
(-4250 4900);
DISPLAY 0.680851 (-4250 4900);
PAINT MONO (-4250 4900);
DISPLAY INVISIBLE (-4250 4900);
FORCEPROP 2 LAST BOM_COST SM_THERM
J 0
(-4250 4950);
DISPLAY 1.021277 (-4250 4950);
PAINT ORANGE (-4250 4950);
DISPLAY INVISIBLE (-4250 4950);
FORCEPROP 2 LAST SEC_TYPE TSSOP
J 0
(-4250 4900);
DISPLAY 1.021277 (-4250 4900);
PAINT ORANGE (-4250 4900);
DISPLAY INVISIBLE (-4250 4900);
FORCEPROP 1 LAST PACK_TYPE TSSOP
J 0
(-4250 4900);
PAINT SKYBLUE (-4250 4900);
DISPLAY INVISIBLE (-4250 4900);
FORCEPROP 2 LAST CDS_LIB mstr_analog
J 0
(-4000 4450);
PAINT ORANGE (-4000 4450);
DISPLAY INVISIBLE (-4000 4450);
FORCEPROP 1 LAST PATH I1
J 0
(-4000 4800);
PAINT GREEN (-4000 4800);
DISPLAY INVISIBLE (-4000 4800);
FORCEADD RES..2
(-4775 4075);
FORCEPROP 1 LASTPIN (-4775 3975) $PN 2
J 0
(-4770 3985);
DISPLAY 0.617021 (-4770 3985);
PAINT ORANGE (-4770 3985);
FORCEPROP 1 LAST MATERIAL CHIP
J 0
(-4735 4000);
DISPLAY 0.617021 (-4735 4000);
PAINT SKYBLUE (-4735 4000);
FORCEPROP 1 LAST PACK_TYPE 0402
J 0
(-4735 3900);
DISPLAY 0.617021 (-4735 3900);
PAINT SKYBLUE (-4735 3900);
FORCEPROP 1 LAST WATTAGE 1/16W
J 0
(-4735 4050);
DISPLAY 0.617021 (-4735 4050);
PAINT SKYBLUE (-4735 4050);
FORCEPROP 1 LAST PART_NUMBER G21796-026
J 0
(-4735 3950);
DISPLAY 0.617021 (-4735 3950);
PAINT BLUE (-4735 3950);
FORCEPROP 1 LASTPIN (-4775 4175) $PN 1
J 0
(-4770 4137);
DISPLAY 0.617021 (-4770 4137);
PAINT ORANGE (-4770 4137);
FORCEPROP 1 LAST LOCATION R9B8
J 0
(-4730 4200);
DISPLAY 0.617021 (-4730 4200);
PAINT AQUA (-4730 4200);
FORCEPROP 1 LAST TOLERANCE 1%
J 0
(-4730 4100);
DISPLAY 0.617021 (-4730 4100);
PAINT SKYBLUE (-4730 4100);
FORCEPROP 1 LAST VALUE 1.00K
J 0
(-4730 4150);
DISPLAY 0.617021 (-4730 4150);
PAINT SKYBLUE (-4730 4150);
FORCEPROP 2 LAST CDS_LIB mstr_discrete
J 0
(-4775 4075);
PAINT ORANGE (-4775 4075);
DISPLAY INVISIBLE (-4775 4075);
FORCEPROP 2 LAST BOM_COST SM_THERM
J 0
(-4725 4300);
DISPLAY 1.021277 (-4725 4300);
PAINT ORANGE (-4725 4300);
DISPLAY INVISIBLE (-4725 4300);
FORCEPROP 2 LAST SEC_TYPE 0402
J 0
(-4725 4300);
DISPLAY 1.021277 (-4725 4300);
PAINT ORANGE (-4725 4300);
DISPLAY INVISIBLE (-4725 4300);
FORCEPROP 0 LAST SEC 1
J 0
(-4725 4250);
DISPLAY 0.680851 (-4725 4250);
PAINT MONO (-4725 4250);
DISPLAY INVISIBLE (-4725 4250);
FORCEPROP 2 LAST CDS_LOCATION R9B8
J 0
(-4730 4200);
DISPLAY 0.617021 (-4730 4200);
PAINT AQUA (-4730 4200);
DISPLAY INVISIBLE (-4730 4200);
FORCEPROP 1 LAST PATH I10
J 0
(-4725 4250);
DISPLAY 0.978723 (-4725 4250);
PAINT WHITE (-4725 4250);
DISPLAY INVISIBLE (-4725 4250);
FORCEPROP 2 LAST ROOM TEMP_SENSORS
J 0
(-4725 4250);
DISPLAY 1.021277 (-4725 4250);
PAINT ORANGE (-4725 4250);
DISPLAY INVISIBLE (-4725 4250);
FORCEADD GND..1
(-4775 3850);
FORCEPROP 3 LASTPIN (-4775 3900) SIG_NAME GND\g
J 0
(-4765 3910);
DISPLAY 0.659574 (-4765 3910);
PAINT MONO (-4765 3910);
DISPLAY INVISIBLE (-4765 3910);
FORCEPROP 1 LAST BODY_TYPE PLUMBING
J 0
(-4820 3807);
DISPLAY 0.340426 (-4820 3807);
PAINT GREEN (-4820 3807);
DISPLAY INVISIBLE (-4820 3807);
FORCEPROP 1 LAST SIZE 1B
J 0
(-4700 3800);
DISPLAY 0.872340 (-4700 3800);
PAINT AQUA (-4700 3800);
DISPLAY INVISIBLE (-4700 3800);
FORCEPROP 1 LAST VOLTAGE 0.0V
J 0
(-4820 3807);
DISPLAY 0.340426 (-4820 3807);
PAINT SKYBLUE (-4820 3807);
DISPLAY INVISIBLE (-4820 3807);
FORCEPROP 2 LAST CDS_LIB mstr_symbols
J 0
(-4775 3850);
PAINT ORANGE (-4775 3850);
DISPLAY INVISIBLE (-4775 3850);
FORCEPROP 1 LAST HDL_POWER GND
J 0
(-4775 4000);
DISPLAY 0.872340 (-4775 4000);
PAINT GREEN (-4775 4000);
DISPLAY INVISIBLE (-4775 4000);
FORCEPROP 1 LAST PATH I12
J 0
(-4700 3850);
DISPLAY 0.872340 (-4700 3850);
PAINT AQUA (-4700 3850);
DISPLAY INVISIBLE (-4700 3850);
FORCEADD P3V3_STBY..1
(-4350 5150);
FORCEPROP 3 LASTPIN (-4350 5100) SIG_NAME P3V3_STBY\g
J 0
(-4340 5110);
DISPLAY 0.659574 (-4340 5110);
PAINT MONO (-4340 5110);
DISPLAY INVISIBLE (-4340 5110);
FORCEPROP 1 LAST HDL_POWER P3V3_STBY
J 0
(-4650 5025);
DISPLAY 0.872340 (-4650 5025);
PAINT ORANGE (-4650 5025);
DISPLAY INVISIBLE (-4650 5025);
FORCEPROP 1 LAST BODY_TYPE PLUMBING
J 0
(-4395 5107);
DISPLAY 0.340426 (-4395 5107);
PAINT GREEN (-4395 5107);
DISPLAY INVISIBLE (-4395 5107);
FORCEPROP 1 LAST VOLTAGE 3.3V
J 0
(-4395 5107);
DISPLAY 0.340426 (-4395 5107);
PAINT SKYBLUE (-4395 5107);
DISPLAY INVISIBLE (-4395 5107);
FORCEPROP 1 LAST PATH I14
J 0
(-4305 5152);
DISPLAY 0.340426 (-4305 5152);
PAINT GREEN (-4305 5152);
DISPLAY INVISIBLE (-4305 5152);
FORCEPROP 1 LAST SIZE 1B
J 0
(-4305 5172);
DISPLAY 0.340426 (-4305 5172);
PAINT GREEN (-4305 5172);
DISPLAY INVISIBLE (-4305 5172);
FORCEPROP 2 LAST CDS_LIB mstr_symbols
J 0
(-4350 5150);
PAINT ORANGE (-4350 5150);
DISPLAY INVISIBLE (-4350 5150);
FORCEADD GND..1
(-3400 3850);
FORCEPROP 3 LASTPIN (-3400 3900) SIG_NAME GND\g
J 0
(-3390 3910);
DISPLAY 0.659574 (-3390 3910);
PAINT MONO (-3390 3910);
DISPLAY INVISIBLE (-3390 3910);
FORCEPROP 1 LAST HDL_POWER GND
J 0
(-3400 4000);
DISPLAY 0.872340 (-3400 4000);
PAINT GREEN (-3400 4000);
DISPLAY INVISIBLE (-3400 4000);
FORCEPROP 1 LAST PATH I15
J 0
(-3325 3850);
DISPLAY 0.872340 (-3325 3850);
PAINT AQUA (-3325 3850);
DISPLAY INVISIBLE (-3325 3850);
FORCEPROP 1 LAST BODY_TYPE PLUMBING
J 0
(-3445 3807);
DISPLAY 0.340426 (-3445 3807);
PAINT GREEN (-3445 3807);
DISPLAY INVISIBLE (-3445 3807);
FORCEPROP 1 LAST SIZE 1B
J 0
(-3325 3800);
DISPLAY 0.872340 (-3325 3800);
PAINT AQUA (-3325 3800);
DISPLAY INVISIBLE (-3325 3800);
FORCEPROP 2 LAST CDS_LIB mstr_symbols
J 0
(-3400 3850);
PAINT ORANGE (-3400 3850);
DISPLAY INVISIBLE (-3400 3850);
FORCEPROP 1 LAST VOLTAGE 0.0V
J 0
(-3445 3807);
DISPLAY 0.340426 (-3445 3807);
PAINT SKYBLUE (-3445 3807);
DISPLAY INVISIBLE (-3445 3807);
FORCEADD OFFPAGE..4
(-1475 4500);
FORCEPROP 2 LAST $XR0 167 
J 0
(-1289 4500);
DISPLAY 0.638298 (-1289 4500);
PAINT MONO (-1289 4500);
FORCEPROP 2 LAST $XR1 184 
J 0
(-1169 4500);
DISPLAY 0.638298 (-1169 4500);
PAINT MONO (-1169 4500);
FORCEPROP 2 LAST $XR2 191 
J 0
(-1049 4500);
DISPLAY 0.638298 (-1049 4500);
PAINT MONO (-1049 4500);
FORCEPROP 1 LAST COMMENT_BODY TRUE
J 0
(-1500 4400);
DISPLAY 0.872340 (-1500 4400);
PAINT GREEN (-1500 4400);
DISPLAY INVISIBLE (-1500 4400);
FORCEPROP 2 LAST CDS_LIB mstr_standard
J 0
(-1475 4500);
PAINT ORANGE (-1475 4500);
DISPLAY INVISIBLE (-1475 4500);
FORCEPROP 1 LAST OFFPAGE TRUE
J 0
(-1150 4375);
DISPLAY 0.872340 (-1150 4375);
PAINT GREEN (-1150 4375);
DISPLAY INVISIBLE (-1150 4375);
FORCEPROP 2 LAST PATH I16
J 0
(-1425 4575);
DISPLAY 1.021277 (-1425 4575);
PAINT ORANGE (-1425 4575);
DISPLAY INVISIBLE (-1425 4575);
FORCEADD OFFPAGE..3
(-1475 4450);
FORCEPROP 2 LAST $XR0 167 
J 0
(-1261 4450);
DISPLAY 0.638298 (-1261 4450);
PAINT MONO (-1261 4450);
FORCEPROP 2 LAST $XR1 184 
J 0
(-1141 4450);
DISPLAY 0.638298 (-1141 4450);
PAINT MONO (-1141 4450);
FORCEPROP 2 LAST $XR2 191 
J 0
(-1021 4450);
DISPLAY 0.638298 (-1021 4450);
PAINT MONO (-1021 4450);
FORCEPROP 1 LAST COMMENT_BODY TRUE
J 0
(-1525 4350);
DISPLAY 0.872340 (-1525 4350);
PAINT GREEN (-1525 4350);
DISPLAY INVISIBLE (-1525 4350);
FORCEPROP 2 LAST CDS_LIB mstr_standard
J 0
(-1475 4450);
PAINT ORANGE (-1475 4450);
DISPLAY INVISIBLE (-1475 4450);
FORCEPROP 2 LAST PATH I17
J 0
(-1425 4525);
DISPLAY 1.021277 (-1425 4525);
PAINT ORANGE (-1425 4525);
DISPLAY INVISIBLE (-1425 4525);
FORCEPROP 1 LAST OFFPAGE TRUE
J 0
(-1150 4325);
DISPLAY 0.872340 (-1150 4325);
PAINT GREEN (-1150 4325);
DISPLAY INVISIBLE (-1150 4325);
FORCEADD GND..1
(-3225 2400);
FORCEPROP 3 LASTPIN (-3225 2450) SIG_NAME GND\g
J 0
(-3215 2460);
DISPLAY 0.659574 (-3215 2460);
PAINT MONO (-3215 2460);
DISPLAY INVISIBLE (-3215 2460);
FORCEPROP 1 LAST PATH I22
J 0
(-3150 2400);
DISPLAY 0.872340 (-3150 2400);
PAINT AQUA (-3150 2400);
DISPLAY INVISIBLE (-3150 2400);
FORCEPROP 1 LAST BODY_TYPE PLUMBING
J 0
(-3270 2357);
DISPLAY 0.340426 (-3270 2357);
PAINT GREEN (-3270 2357);
DISPLAY INVISIBLE (-3270 2357);
FORCEPROP 2 LAST CDS_LIB mstr_symbols
J 0
(-3225 2400);
PAINT ORANGE (-3225 2400);
DISPLAY INVISIBLE (-3225 2400);
FORCEPROP 1 LAST SIZE 1B
J 0
(-3150 2350);
DISPLAY 0.872340 (-3150 2350);
PAINT AQUA (-3150 2350);
DISPLAY INVISIBLE (-3150 2350);
FORCEPROP 1 LAST VOLTAGE 0.0V
J 0
(-3270 2357);
DISPLAY 0.340426 (-3270 2357);
PAINT SKYBLUE (-3270 2357);
DISPLAY INVISIBLE (-3270 2357);
FORCEPROP 1 LAST HDL_POWER GND
J 0
(-3225 2550);
DISPLAY 0.872340 (-3225 2550);
PAINT GREEN (-3225 2550);
DISPLAY INVISIBLE (-3225 2550);
FORCEADD P3V3_STBY..1
(-4175 3700);
FORCEPROP 3 LASTPIN (-4175 3650) SIG_NAME P3V3_STBY\g
J 0
(-4165 3660);
DISPLAY 0.659574 (-4165 3660);
PAINT MONO (-4165 3660);
DISPLAY INVISIBLE (-4165 3660);
FORCEPROP 1 LAST HDL_POWER P3V3_STBY
J 0
(-4475 3575);
DISPLAY 0.872340 (-4475 3575);
PAINT ORANGE (-4475 3575);
DISPLAY INVISIBLE (-4475 3575);
FORCEPROP 1 LAST PATH I23
J 0
(-4130 3702);
DISPLAY 0.340426 (-4130 3702);
PAINT GREEN (-4130 3702);
DISPLAY INVISIBLE (-4130 3702);
FORCEPROP 1 LAST BODY_TYPE PLUMBING
J 0
(-4220 3657);
DISPLAY 0.340426 (-4220 3657);
PAINT GREEN (-4220 3657);
DISPLAY INVISIBLE (-4220 3657);
FORCEPROP 2 LAST CDS_LIB mstr_symbols
J 0
(-4175 3700);
PAINT ORANGE (-4175 3700);
DISPLAY INVISIBLE (-4175 3700);
FORCEPROP 1 LAST SIZE 1B
J 0
(-4130 3722);
DISPLAY 0.340426 (-4130 3722);
PAINT GREEN (-4130 3722);
DISPLAY INVISIBLE (-4130 3722);
FORCEPROP 1 LAST VOLTAGE 3.3V
J 0
(-4220 3657);
DISPLAY 0.340426 (-4220 3657);
PAINT SKYBLUE (-4220 3657);
DISPLAY INVISIBLE (-4220 3657);
FORCEADD CAP..1
(-4675 3175);
FORCEPROP 1 LASTPIN (-4675 3075) $PN 2
J 0
(-4665 3055);
DISPLAY 0.617021 (-4665 3055);
PAINT ORANGE (-4665 3055);
FORCEPROP 1 LAST PART_NUMBER A36095-025
J 0
(-4625 3050);
DISPLAY 0.617021 (-4625 3050);
PAINT BLUE (-4625 3050);
FORCEPROP 1 LASTPIN (-4675 3275) $PN 1
J 0
(-4665 3255);
DISPLAY 0.617021 (-4665 3255);
PAINT ORANGE (-4665 3255);
FORCEPROP 1 LAST VOLTAGE 50V
J 0
(-4625 3175);
DISPLAY 0.617021 (-4625 3175);
PAINT SKYBLUE (-4625 3175);
FORCEPROP 1 LAST TOLERANCE 5%
J 0
(-4625 3125);
DISPLAY 0.617021 (-4625 3125);
PAINT SKYBLUE (-4625 3125);
FORCEPROP 1 LAST VALUE 47.0PF
J 0
(-4625 3225);
DISPLAY 0.617021 (-4625 3225);
PAINT SKYBLUE (-4625 3225);
FORCEPROP 1 LAST LOCATION C1E19
J 0
(-4625 3275);
DISPLAY 0.617021 (-4625 3275);
PAINT AQUA (-4625 3275);
FORCEPROP 1 LAST PACK_TYPE 0402LF
J 0
(-4550 3125);
DISPLAY 0.617021 (-4550 3125);
PAINT SKYBLUE (-4550 3125);
FORCEPROP 1 LAST MATERIAL EMPTY
J 0
(-4550 3075);
DISPLAY 0.617021 (-4550 3075);
PAINT RED (-4550 3075);
FORCEPROP 2 LAST CDS_LIB mstr_discrete
J 0
(-4675 3175);
PAINT ORANGE (-4675 3175);
DISPLAY INVISIBLE (-4675 3175);
FORCEPROP 2 LAST CDS_LOCATION C1E19
J 0
(-4625 3275);
DISPLAY 0.617021 (-4625 3275);
PAINT AQUA (-4625 3275);
DISPLAY INVISIBLE (-4625 3275);
FORCEPROP 2 LAST ROOM TEMP_SENSORS
J 0
(-4625 3325);
DISPLAY 1.021277 (-4625 3325);
PAINT ORANGE (-4625 3325);
DISPLAY INVISIBLE (-4625 3325);
FORCEPROP 1 LAST PATH I24
J 0
(-4625 3325);
DISPLAY 0.978723 (-4625 3325);
PAINT WHITE (-4625 3325);
DISPLAY INVISIBLE (-4625 3325);
FORCEPROP 0 LAST SEC 1
J 0
(-4625 3325);
DISPLAY 0.680851 (-4625 3325);
PAINT MONO (-4625 3325);
DISPLAY INVISIBLE (-4625 3325);
FORCEPROP 2 LAST BOM_COST SM_THERM
J 0
(-4625 3375);
DISPLAY 1.021277 (-4625 3375);
PAINT ORANGE (-4625 3375);
DISPLAY INVISIBLE (-4625 3375);
FORCEPROP 2 LAST SEC_TYPE 0402LF
J 0
(-4625 3375);
DISPLAY 1.021277 (-4625 3375);
PAINT ORANGE (-4625 3375);
DISPLAY INVISIBLE (-4625 3375);
FORCEADD RES..1
(-5000 3325);
FORCEPROP 1 LAST WATTAGE 1/16W
J 2
(-5025 3175);
DISPLAY 0.617021 (-5025 3175);
PAINT SKYBLUE (-5025 3175);
FORCEPROP 1 LAST VALUE 49.9
J 2
(-5025 3225);
DISPLAY 0.617021 (-5025 3225);
PAINT SKYBLUE (-5025 3225);
FORCEPROP 1 LAST MATERIAL CHIP
J 0
(-5000 3175);
DISPLAY 0.617021 (-5000 3175);
PAINT SKYBLUE (-5000 3175);
FORCEPROP 1 LAST TOLERANCE 1%
J 0
(-5000 3225);
DISPLAY 0.617021 (-5000 3225);
PAINT SKYBLUE (-5000 3225);
FORCEPROP 1 LASTPIN (-5100 3325) $PN 1
J 0
(-5088 3337);
DISPLAY 0.617021 (-5088 3337);
PAINT ORANGE (-5088 3337);
FORCEPROP 1 LASTPIN (-4900 3325) $PN 2
J 0
(-4938 3337);
DISPLAY 0.617021 (-4938 3337);
PAINT ORANGE (-4938 3337);
FORCEPROP 1 LAST LOCATION R9R5
J 0
(-5050 3375);
DISPLAY 0.617021 (-5050 3375);
PAINT AQUA (-5050 3375);
FORCEPROP 1 LAST PACK_TYPE 0402
J 0
(-4925 3225);
DISPLAY 0.617021 (-4925 3225);
PAINT SKYBLUE (-4925 3225);
FORCEPROP 1 LAST PART_NUMBER G21796-047
J 0
(-5050 3425);
DISPLAY 0.617021 (-5050 3425);
PAINT BLUE (-5050 3425);
FORCEPROP 2 LAST CDS_LIB mstr_discrete
J 0
(-5000 3325);
PAINT ORANGE (-5000 3325);
DISPLAY INVISIBLE (-5000 3325);
FORCEPROP 2 LAST ROOM TEMP_SENSORS
J 0
(-5050 3475);
DISPLAY 1.021277 (-5050 3475);
PAINT ORANGE (-5050 3475);
DISPLAY INVISIBLE (-5050 3475);
FORCEPROP 1 LAST PATH I25
J 0
(-5050 3475);
DISPLAY 0.978723 (-5050 3475);
PAINT WHITE (-5050 3475);
DISPLAY INVISIBLE (-5050 3475);
FORCEPROP 2 LAST CDS_LOCATION R9R5
J 0
(-5050 3375);
DISPLAY 0.617021 (-5050 3375);
PAINT AQUA (-5050 3375);
DISPLAY INVISIBLE (-5050 3375);
FORCEPROP 0 LAST SEC 1
J 0
(-5050 3475);
DISPLAY 0.680851 (-5050 3475);
PAINT MONO (-5050 3475);
DISPLAY INVISIBLE (-5050 3475);
FORCEPROP 2 LAST BOM_COST SM_THERM
J 0
(-5050 3525);
DISPLAY 1.021277 (-5050 3525);
PAINT ORANGE (-5050 3525);
DISPLAY INVISIBLE (-5050 3525);
FORCEPROP 2 LAST SEC_TYPE 0402
J 0
(-5050 3525);
DISPLAY 1.021277 (-5050 3525);
PAINT ORANGE (-5050 3525);
DISPLAY INVISIBLE (-5050 3525);
FORCEADD RES..1
(-4975 3000);
FORCEPROP 1 LAST MATERIAL CHIP
J 0
(-5375 2950);
DISPLAY 0.617021 (-5375 2950);
PAINT SKYBLUE (-5375 2950);
FORCEPROP 1 LAST VALUE 49.9
J 2
(-5150 2950);
DISPLAY 0.617021 (-5150 2950);
PAINT SKYBLUE (-5150 2950);
FORCEPROP 1 LASTPIN (-5075 3000) $PN 1
J 0
(-5063 3012);
DISPLAY 0.617021 (-5063 3012);
PAINT ORANGE (-5063 3012);
FORCEPROP 1 LASTPIN (-4875 3000) $PN 2
J 0
(-4913 3012);
DISPLAY 0.617021 (-4913 3012);
PAINT ORANGE (-4913 3012);
FORCEPROP 1 LAST TOLERANCE 1%
J 0
(-4925 2950);
DISPLAY 0.617021 (-4925 2950);
PAINT SKYBLUE (-4925 2950);
FORCEPROP 1 LAST WATTAGE 1/16W
J 2
(-4750 2950);
DISPLAY 0.617021 (-4750 2950);
PAINT SKYBLUE (-4750 2950);
FORCEPROP 1 LAST PACK_TYPE 0402
J 0
(-4725 2850);
DISPLAY 0.617021 (-4725 2850);
PAINT SKYBLUE (-4725 2850);
FORCEPROP 1 LAST LOCATION R9R6
J 0
(-5025 3050);
DISPLAY 0.617021 (-5025 3050);
PAINT AQUA (-5025 3050);
FORCEPROP 1 LAST PART_NUMBER G21796-047
J 0
(-5025 3100);
DISPLAY 0.617021 (-5025 3100);
PAINT BLUE (-5025 3100);
FORCEPROP 2 LAST CDS_LIB mstr_discrete
J 0
(-4975 3000);
PAINT ORANGE (-4975 3000);
DISPLAY INVISIBLE (-4975 3000);
FORCEPROP 2 LAST CDS_LOCATION R9R6
J 0
(-5025 3050);
DISPLAY 0.617021 (-5025 3050);
PAINT AQUA (-5025 3050);
DISPLAY INVISIBLE (-5025 3050);
FORCEPROP 2 LAST ROOM TEMP_SENSORS
J 0
(-5025 3150);
DISPLAY 1.021277 (-5025 3150);
PAINT ORANGE (-5025 3150);
DISPLAY INVISIBLE (-5025 3150);
FORCEPROP 2 LAST BOM_COST SM_THERM
J 0
(-5025 3200);
DISPLAY 1.021277 (-5025 3200);
PAINT ORANGE (-5025 3200);
DISPLAY INVISIBLE (-5025 3200);
FORCEPROP 2 LAST SEC_TYPE 0402
J 0
(-5025 3200);
DISPLAY 1.021277 (-5025 3200);
PAINT ORANGE (-5025 3200);
DISPLAY INVISIBLE (-5025 3200);
FORCEPROP 0 LAST SEC 1
J 0
(-5025 3150);
DISPLAY 0.680851 (-5025 3150);
PAINT MONO (-5025 3150);
DISPLAY INVISIBLE (-5025 3150);
FORCEPROP 1 LAST PATH I26
J 0
(-5025 3150);
DISPLAY 0.978723 (-5025 3150);
PAINT WHITE (-5025 3150);
DISPLAY INVISIBLE (-5025 3150);
FORCEADD PNP..3
(-5700 3150);
FORCEPROP 1 LAST PART_NUMBER G73554-001
J 2
(-5875 3100);
DISPLAY 0.617021 (-5875 3100);
PAINT BLUE (-5875 3100);
FORCEPROP 1 LASTPIN (-5750 3050) $PN 3
J 0
(-5725 3000);
DISPLAY 0.617021 (-5725 3000);
PAINT WHITE (-5725 3000);
FORCEPROP 1 LAST PACK_TYPE TO92
J 2
(-5825 3050);
DISPLAY 0.617021 (-5825 3050);
PAINT SKYBLUE (-5825 3050);
FORCEPROP 1 LAST VALUE MPS2907
J 2
(-5825 3150);
DISPLAY 0.617021 (-5825 3150);
PAINT SKYBLUE (-5825 3150);
FORCEPROP 1 LAST LOCATION Q1E1
J 2
(-5825 3200);
DISPLAY 0.617021 (-5825 3200);
PAINT AQUA (-5825 3200);
FORCEPROP 1 LAST MATERIAL IC
J 2
(-5825 3100);
DISPLAY 0.617021 (-5825 3100);
PAINT SKYBLUE (-5825 3100);
FORCEPROP 1 LASTPIN (-5750 3250) $PN 2
J 0
(-5725 3250);
DISPLAY 0.617021 (-5725 3250);
PAINT WHITE (-5725 3250);
FORCEPROP 1 LASTPIN (-5600 3150) $PN 1
J 0
(-5600 3100);
DISPLAY 0.617021 (-5600 3100);
PAINT WHITE (-5600 3100);
FORCEPROP 2 LAST ROOM TEMP_SENSORS
J 0
(-5825 3250);
DISPLAY 1.021277 (-5825 3250);
PAINT ORANGE (-5825 3250);
DISPLAY INVISIBLE (-5825 3250);
FORCEPROP 1 LAST PATH I27
J 2
(-5825 3250);
DISPLAY 0.978723 (-5825 3250);
PAINT BLUE (-5825 3250);
DISPLAY INVISIBLE (-5825 3250);
FORCEPROP 2 LAST CDS_LOCATION Q1E1
J 2
(-5825 3200);
DISPLAY 0.617021 (-5825 3200);
PAINT AQUA (-5825 3200);
DISPLAY INVISIBLE (-5825 3200);
FORCEPROP 2 LAST CDS_LIB mstr_discrete
J 0
(-5700 3150);
PAINT ORANGE (-5700 3150);
DISPLAY INVISIBLE (-5700 3150);
FORCEPROP 2 LAST SEC 1
J 0
(-5825 3300);
DISPLAY 0.680851 (-5825 3300);
PAINT MONO (-5825 3300);
DISPLAY INVISIBLE (-5825 3300);
FORCEPROP 2 LAST BOM_COST SM_THERM
J 0
(-5825 3300);
DISPLAY 1.021277 (-5825 3300);
PAINT ORANGE (-5825 3300);
DISPLAY INVISIBLE (-5825 3300);
FORCEPROP 2 LAST SEC_TYPE TO92
J 0
(-5825 3300);
DISPLAY 1.021277 (-5825 3300);
PAINT ORANGE (-5825 3300);
DISPLAY INVISIBLE (-5825 3300);
FORCEADD P3V3_STBY..1
(-6400 3075);
FORCEPROP 3 LASTPIN (-6400 3025) SIG_NAME P3V3_STBY\g
J 0
(-6390 3035);
DISPLAY 0.659574 (-6390 3035);
PAINT MONO (-6390 3035);
DISPLAY INVISIBLE (-6390 3035);
FORCEPROP 1 LAST HDL_POWER P3V3_STBY
J 0
(-6700 2950);
DISPLAY 0.872340 (-6700 2950);
PAINT ORANGE (-6700 2950);
DISPLAY INVISIBLE (-6700 2950);
FORCEPROP 1 LAST VOLTAGE 3.3V
J 0
(-6445 3032);
DISPLAY 0.340426 (-6445 3032);
PAINT SKYBLUE (-6445 3032);
DISPLAY INVISIBLE (-6445 3032);
FORCEPROP 1 LAST BODY_TYPE PLUMBING
J 0
(-6445 3032);
DISPLAY 0.340426 (-6445 3032);
PAINT GREEN (-6445 3032);
DISPLAY INVISIBLE (-6445 3032);
FORCEPROP 1 LAST PATH I29
J 0
(-6355 3077);
DISPLAY 0.340426 (-6355 3077);
PAINT GREEN (-6355 3077);
DISPLAY INVISIBLE (-6355 3077);
FORCEPROP 1 LAST SIZE 1B
J 0
(-6355 3097);
DISPLAY 0.340426 (-6355 3097);
PAINT GREEN (-6355 3097);
DISPLAY INVISIBLE (-6355 3097);
FORCEPROP 2 LAST CDS_LIB mstr_symbols
J 0
(-6400 3075);
PAINT ORANGE (-6400 3075);
DISPLAY INVISIBLE (-6400 3075);
FORCEADD PNP..3
(-5775 4600);
FORCEPROP 1 LAST PART_NUMBER G73554-001
J 2
(-5950 4550);
DISPLAY 0.617021 (-5950 4550);
PAINT BLUE (-5950 4550);
FORCEPROP 1 LAST MATERIAL IC
J 2
(-5900 4550);
DISPLAY 0.617021 (-5900 4550);
PAINT SKYBLUE (-5900 4550);
FORCEPROP 1 LAST PACK_TYPE TO92
J 2
(-5900 4500);
DISPLAY 0.617021 (-5900 4500);
PAINT SKYBLUE (-5900 4500);
FORCEPROP 1 LASTPIN (-5825 4500) $PN 3
J 0
(-5800 4450);
DISPLAY 0.617021 (-5800 4450);
PAINT WHITE (-5800 4450);
FORCEPROP 1 LASTPIN (-5675 4600) $PN 1
J 0
(-5675 4550);
DISPLAY 0.617021 (-5675 4550);
PAINT WHITE (-5675 4550);
FORCEPROP 1 LAST VALUE MPS2907
J 2
(-5900 4600);
DISPLAY 0.617021 (-5900 4600);
PAINT SKYBLUE (-5900 4600);
FORCEPROP 1 LAST LOCATION Q9B1
J 2
(-5900 4650);
DISPLAY 0.617021 (-5900 4650);
PAINT AQUA (-5900 4650);
FORCEPROP 1 LASTPIN (-5825 4700) $PN 2
J 0
(-5800 4700);
DISPLAY 0.617021 (-5800 4700);
PAINT WHITE (-5800 4700);
FORCEPROP 2 LAST CDS_LIB mstr_discrete
J 0
(-5775 4600);
PAINT ORANGE (-5775 4600);
DISPLAY INVISIBLE (-5775 4600);
FORCEPROP 2 LAST ROOM TEMP_SENSORS
J 0
(-5900 4700);
DISPLAY 1.021277 (-5900 4700);
PAINT ORANGE (-5900 4700);
DISPLAY INVISIBLE (-5900 4700);
FORCEPROP 1 LAST PATH I3
J 2
(-5900 4700);
DISPLAY 0.978723 (-5900 4700);
PAINT BLUE (-5900 4700);
DISPLAY INVISIBLE (-5900 4700);
FORCEPROP 2 LAST CDS_LOCATION Q9B1
J 2
(-5900 4650);
DISPLAY 0.617021 (-5900 4650);
PAINT AQUA (-5900 4650);
DISPLAY INVISIBLE (-5900 4650);
FORCEPROP 2 LAST SEC_TYPE TO92
J 0
(-5900 4750);
DISPLAY 1.021277 (-5900 4750);
PAINT ORANGE (-5900 4750);
DISPLAY INVISIBLE (-5900 4750);
FORCEPROP 2 LAST BOM_COST SM_THERM
J 0
(-5900 4750);
DISPLAY 1.021277 (-5900 4750);
PAINT ORANGE (-5900 4750);
DISPLAY INVISIBLE (-5900 4750);
FORCEPROP 2 LAST SEC 1
J 0
(-5900 4750);
DISPLAY 0.680851 (-5900 4750);
PAINT MONO (-5900 4750);
DISPLAY INVISIBLE (-5900 4750);
FORCEADD TMP421..1
(-3825 3000);
FORCEPROP 2 LASTPIN (-4125 2850) $PN 4
J 2
(-4135 2860);
DISPLAY 0.617021 (-4135 2860);
PAINT ORANGE (-4135 2860);
FORCEPROP 2 LASTPIN (-4125 2900) $PN 3
J 2
(-4135 2910);
DISPLAY 0.617021 (-4135 2910);
PAINT ORANGE (-4135 2910);
FORCEPROP 2 LASTPIN (-4125 3000) $PN 2
J 2
(-4135 3010);
DISPLAY 0.617021 (-4135 3010);
PAINT ORANGE (-4135 3010);
FORCEPROP 2 LASTPIN (-4125 3050) $PN 1
J 2
(-4135 3060);
DISPLAY 0.617021 (-4135 3060);
PAINT ORANGE (-4135 3060);
FORCEPROP 2 LASTPIN (-4125 3150) $PN 8
J 2
(-4135 3160);
DISPLAY 0.617021 (-4135 3160);
PAINT ORANGE (-4135 3160);
FORCEPROP 1 LAST PART_NUMBER G62962-001
J 0
(-4075 2700);
DISPLAY 0.617021 (-4075 2700);
PAINT BLUE (-4075 2700);
FORCEPROP 2 LASTPIN (-3525 2800) $PN 5
J 0
(-3515 2810);
DISPLAY 0.617021 (-3515 2810);
PAINT ORANGE (-3515 2810);
FORCEPROP 2 LASTPIN (-3525 3000) $PN 7
J 0
(-3515 3010);
DISPLAY 0.617021 (-3515 3010);
PAINT ORANGE (-3515 3010);
FORCEPROP 2 LASTPIN (-3525 3050) $PN 6
J 0
(-3515 3060);
DISPLAY 0.617021 (-3515 3060);
PAINT ORANGE (-3515 3060);
FORCEPROP 1 LAST MATERIAL IC
J 0
(-4075 3350);
DISPLAY 0.617021 (-4075 3350);
PAINT SKYBLUE (-4075 3350);
FORCEPROP 1 LAST LOCATION U1E1
J 0
(-4075 3400);
DISPLAY 0.617021 (-4075 3400);
PAINT AQUA (-4075 3400);
FORCEPROP 2 LAST CDS_LIB mstr_analog
J 0
(-3825 3000);
PAINT ORANGE (-3825 3000);
DISPLAY INVISIBLE (-3825 3000);
FORCEPROP 2 LAST ROOM TEMP_SENSORS
J 0
(-4075 3450);
DISPLAY 1.021277 (-4075 3450);
PAINT ORANGE (-4075 3450);
DISPLAY INVISIBLE (-4075 3450);
FORCEPROP 1 LAST PATH I30
J 0
(-3825 3350);
PAINT GREEN (-3825 3350);
DISPLAY INVISIBLE (-3825 3350);
FORCEPROP 2 LAST CDS_LOCATION U1E1
J 0
(-4075 3400);
DISPLAY 0.617021 (-4075 3400);
PAINT AQUA (-4075 3400);
DISPLAY INVISIBLE (-4075 3400);
FORCEPROP 2 LAST SEC 1
J 0
(-4075 3450);
DISPLAY 0.680851 (-4075 3450);
PAINT MONO (-4075 3450);
DISPLAY INVISIBLE (-4075 3450);
FORCEPROP 2 LAST BOM_COST SM_THERM
J 0
(-4075 3500);
DISPLAY 1.021277 (-4075 3500);
PAINT ORANGE (-4075 3500);
DISPLAY INVISIBLE (-4075 3500);
FORCEPROP 2 LAST SEC_TYPE TSSOP
J 0
(-4075 3450);
DISPLAY 1.021277 (-4075 3450);
PAINT ORANGE (-4075 3450);
DISPLAY INVISIBLE (-4075 3450);
FORCEPROP 1 LAST PACK_TYPE TSSOP
J 0
(-4075 3450);
PAINT SKYBLUE (-4075 3450);
DISPLAY INVISIBLE (-4075 3450);
FORCEADD RES..1
(-5050 2850);
FORCEPROP 1 LASTPIN (-5150 2850) $PN 1
J 0
(-5138 2862);
DISPLAY 0.617021 (-5138 2862);
PAINT ORANGE (-5138 2862);
FORCEPROP 1 LAST WATTAGE 1/16W
J 2
(-5075 2700);
DISPLAY 0.617021 (-5075 2700);
PAINT SKYBLUE (-5075 2700);
FORCEPROP 1 LAST VALUE 1.00K
J 2
(-5075 2750);
DISPLAY 0.617021 (-5075 2750);
PAINT SKYBLUE (-5075 2750);
FORCEPROP 1 LAST MATERIAL CHIP
J 0
(-5050 2700);
DISPLAY 0.617021 (-5050 2700);
PAINT SKYBLUE (-5050 2700);
FORCEPROP 1 LAST TOLERANCE 1%
J 0
(-5050 2750);
DISPLAY 0.617021 (-5050 2750);
PAINT SKYBLUE (-5050 2750);
FORCEPROP 1 LAST LOCATION R1E9
J 0
(-5100 2900);
DISPLAY 0.617021 (-5100 2900);
PAINT AQUA (-5100 2900);
FORCEPROP 1 LASTPIN (-4950 2850) $PN 2
J 0
(-4988 2862);
DISPLAY 0.617021 (-4988 2862);
PAINT ORANGE (-4988 2862);
FORCEPROP 1 LAST PART_NUMBER G21796-026
J 0
(-5100 2950);
DISPLAY 0.617021 (-5100 2950);
PAINT BLUE (-5100 2950);
FORCEPROP 1 LAST PACK_TYPE 0402
J 0
(-4800 2700);
DISPLAY 0.617021 (-4800 2700);
PAINT SKYBLUE (-4800 2700);
FORCEPROP 2 LAST CDS_LIB mstr_discrete
J 0
(-5050 2850);
PAINT MONO (-5050 2850);
DISPLAY INVISIBLE (-5050 2850);
FORCEPROP 2 LAST CDS_LOCATION R1E9
J 0
(-5100 2900);
DISPLAY 0.617021 (-5100 2900);
PAINT AQUA (-5100 2900);
DISPLAY INVISIBLE (-5100 2900);
FORCEPROP 1 LAST PATH I34
J 0
(-5100 3000);
DISPLAY 0.978723 (-5100 3000);
PAINT WHITE (-5100 3000);
DISPLAY INVISIBLE (-5100 3000);
FORCEPROP 2 LAST ROOM TEMP_SENSORS
J 0
(-5100 3000);
DISPLAY 1.021277 (-5100 3000);
PAINT ORANGE (-5100 3000);
DISPLAY INVISIBLE (-5100 3000);
FORCEPROP 2 LAST SEC 1
J 0
(-5100 3050);
DISPLAY 0.680851 (-5100 3050);
PAINT MONO (-5100 3050);
DISPLAY INVISIBLE (-5100 3050);
FORCEPROP 2 LAST BOM_COST SM_THERM
J 0
(-5100 3050);
DISPLAY 1.021277 (-5100 3050);
PAINT ORANGE (-5100 3050);
DISPLAY INVISIBLE (-5100 3050);
FORCEPROP 2 LAST SEC_TYPE 0402
J 0
(-5100 3050);
DISPLAY 1.021277 (-5100 3050);
PAINT ORANGE (-5100 3050);
DISPLAY INVISIBLE (-5100 3050);
FORCEADD RES..1
(-5450 4350);
FORCEPROP 1 LAST WATTAGE 1/16W
J 2
(-5575 4300);
DISPLAY 0.617021 (-5575 4300);
PAINT SKYBLUE (-5575 4300);
FORCEPROP 1 LAST LOCATION R9B6
J 0
(-5675 4350);
DISPLAY 0.617021 (-5675 4350);
PAINT AQUA (-5675 4350);
FORCEPROP 1 LAST VALUE 1.00K
J 2
(-5475 4300);
DISPLAY 0.617021 (-5475 4300);
PAINT SKYBLUE (-5475 4300);
FORCEPROP 1 LASTPIN (-5550 4350) $PN 1
J 0
(-5538 4362);
DISPLAY 0.617021 (-5538 4362);
PAINT ORANGE (-5538 4362);
FORCEPROP 1 LASTPIN (-5350 4350) $PN 2
J 0
(-5388 4362);
DISPLAY 0.617021 (-5388 4362);
PAINT ORANGE (-5388 4362);
FORCEPROP 1 LAST MATERIAL CHIP
J 0
(-5475 4300);
DISPLAY 0.617021 (-5475 4300);
PAINT SKYBLUE (-5475 4300);
FORCEPROP 1 LAST TOLERANCE 1%
J 0
(-5375 4300);
DISPLAY 0.617021 (-5375 4300);
PAINT SKYBLUE (-5375 4300);
FORCEPROP 1 LAST PACK_TYPE 0402
J 0
(-5300 4300);
DISPLAY 0.617021 (-5300 4300);
PAINT SKYBLUE (-5300 4300);
FORCEPROP 1 LAST PART_NUMBER G21796-026
J 0
(-5325 4350);
DISPLAY 0.617021 (-5325 4350);
PAINT BLUE (-5325 4350);
FORCEPROP 2 LAST CDS_LOCATION R9B6
J 0
(-5675 4350);
DISPLAY 0.617021 (-5675 4350);
PAINT AQUA (-5675 4350);
DISPLAY INVISIBLE (-5675 4350);
FORCEPROP 2 LAST CDS_LIB mstr_discrete
J 0
(-5450 4350);
PAINT ORANGE (-5450 4350);
DISPLAY INVISIBLE (-5450 4350);
FORCEPROP 2 LAST SEC_TYPE 0402
J 0
(-5500 4550);
DISPLAY 1.021277 (-5500 4550);
PAINT ORANGE (-5500 4550);
DISPLAY INVISIBLE (-5500 4550);
FORCEPROP 2 LAST SEC 1
J 0
(-5500 4550);
DISPLAY 0.680851 (-5500 4550);
PAINT MONO (-5500 4550);
DISPLAY INVISIBLE (-5500 4550);
FORCEPROP 1 LAST PATH I35
J 0
(-5500 4500);
DISPLAY 0.978723 (-5500 4500);
PAINT WHITE (-5500 4500);
DISPLAY INVISIBLE (-5500 4500);
FORCEPROP 2 LAST ROOM TEMP_SENSORS
J 0
(-5400 4525);
DISPLAY 1.021277 (-5400 4525);
PAINT ORANGE (-5400 4525);
DISPLAY INVISIBLE (-5400 4525);
FORCEPROP 2 LAST BOM_COST SM_THERM
J 0
(-5400 4575);
DISPLAY 1.021277 (-5400 4575);
PAINT ORANGE (-5400 4575);
DISPLAY INVISIBLE (-5400 4575);
FORCEADD RES..1
(-4650 2900);
FORCEPROP 1 LAST WATTAGE 1/16W
J 2
(-4675 2750);
DISPLAY 0.617021 (-4675 2750);
PAINT SKYBLUE (-4675 2750);
FORCEPROP 1 LAST VALUE 1.00K
J 2
(-4675 2800);
DISPLAY 0.617021 (-4675 2800);
PAINT SKYBLUE (-4675 2800);
FORCEPROP 1 LASTPIN (-4750 2900) $PN 1
J 0
(-4738 2912);
DISPLAY 0.617021 (-4738 2912);
PAINT ORANGE (-4738 2912);
FORCEPROP 1 LAST MATERIAL CHIP
J 0
(-4650 2750);
DISPLAY 0.617021 (-4650 2750);
PAINT SKYBLUE (-4650 2750);
FORCEPROP 1 LAST TOLERANCE 1%
J 0
(-4650 2800);
DISPLAY 0.617021 (-4650 2800);
PAINT SKYBLUE (-4650 2800);
FORCEPROP 1 LAST PART_NUMBER G21796-026
J 0
(-4800 2650);
DISPLAY 0.617021 (-4800 2650);
PAINT BLUE (-4800 2650);
FORCEPROP 1 LAST LOCATION R1E10
J 0
(-4700 2950);
DISPLAY 0.617021 (-4700 2950);
PAINT AQUA (-4700 2950);
FORCEPROP 1 LASTPIN (-4550 2900) $PN 2
J 0
(-4588 2912);
DISPLAY 0.617021 (-4588 2912);
PAINT ORANGE (-4588 2912);
FORCEPROP 1 LAST PACK_TYPE 0402
J 0
(-4400 2750);
DISPLAY 0.617021 (-4400 2750);
PAINT SKYBLUE (-4400 2750);
FORCEPROP 2 LAST CDS_LIB mstr_discrete
J 0
(-4650 2900);
PAINT ORANGE (-4650 2900);
DISPLAY INVISIBLE (-4650 2900);
FORCEPROP 2 LAST CDS_LOCATION R1E10
J 0
(-4700 2950);
DISPLAY 0.617021 (-4700 2950);
PAINT AQUA (-4700 2950);
DISPLAY INVISIBLE (-4700 2950);
FORCEPROP 2 LAST ROOM TEMP_SENSORS
J 0
(-4700 3000);
DISPLAY 1.021277 (-4700 3000);
PAINT ORANGE (-4700 3000);
DISPLAY INVISIBLE (-4700 3000);
FORCEPROP 1 LAST PATH I38
J 0
(-4700 3050);
DISPLAY 0.978723 (-4700 3050);
PAINT WHITE (-4700 3050);
DISPLAY INVISIBLE (-4700 3050);
FORCEPROP 2 LAST BOM_COST SM_THERM
J 0
(-4700 3050);
DISPLAY 1.021277 (-4700 3050);
PAINT ORANGE (-4700 3050);
DISPLAY INVISIBLE (-4700 3050);
FORCEPROP 2 LAST SEC 1
J 0
(-4700 3100);
PAINT MONO (-4700 3100);
DISPLAY INVISIBLE (-4700 3100);
FORCEPROP 2 LAST SEC_TYPE 0402
J 0
(-4700 3100);
DISPLAY 1.021277 (-4700 3100);
PAINT ORANGE (-4700 3100);
DISPLAY INVISIBLE (-4700 3100);
FORCEADD CAP_A..1
(-7700 4350);
FORCEPROP 1 LASTPIN (-7700 4250) $PN 2
J 0
(-7690 4230);
DISPLAY 0.617021 (-7690 4230);
PAINT ORANGE (-7690 4230);
FORCEPROP 1 LASTPIN (-7700 4450) $PN 1
J 0
(-7690 4430);
DISPLAY 0.617021 (-7690 4430);
PAINT ORANGE (-7690 4430);
FORCEPROP 1 LAST LOCATION C9B7
J 0
(-7650 4450);
DISPLAY 0.617021 (-7650 4450);
PAINT AQUA (-7650 4450);
FORCEPROP 1 LAST PART_NUMBER A36096-030
J 0
(-7650 4200);
DISPLAY 0.617021 (-7650 4200);
PAINT BLUE (-7650 4200);
FORCEPROP 1 LAST VALUE 0.1UF
J 0
(-7650 4400);
DISPLAY 0.617021 (-7650 4400);
PAINT SKYBLUE (-7650 4400);
FORCEPROP 1 LAST TOLERANCE 10%
J 0
(-7650 4300);
DISPLAY 0.617021 (-7650 4300);
PAINT SKYBLUE (-7650 4300);
FORCEPROP 1 LAST PACK_TYPE 0402V
J 0
(-7650 4150);
DISPLAY 0.617021 (-7650 4150);
PAINT SKYBLUE (-7650 4150);
FORCEPROP 1 LAST VOLTAGE 16V
J 0
(-7650 4350);
DISPLAY 0.617021 (-7650 4350);
PAINT SKYBLUE (-7650 4350);
FORCEPROP 1 LAST MATERIAL X7R
J 0
(-7650 4250);
DISPLAY 0.617021 (-7650 4250);
PAINT SKYBLUE (-7650 4250);
FORCEPROP 2 LAST CDS_LIB dev_discrete
J 0
(-7700 4350);
PAINT ORANGE (-7700 4350);
DISPLAY INVISIBLE (-7700 4350);
FORCEPROP 1 LAST PATH I39
J 0
(-7650 4500);
DISPLAY 0.978723 (-7650 4500);
PAINT WHITE (-7650 4500);
DISPLAY INVISIBLE (-7650 4500);
FORCEPROP 2 LAST ROOM TEMP_SENSORS
J 0
(-7650 4500);
DISPLAY 1.021277 (-7650 4500);
PAINT ORANGE (-7650 4500);
DISPLAY INVISIBLE (-7650 4500);
FORCEPROP 2 LAST CDS_LOCATION C9B7
J 0
(-7650 4450);
DISPLAY 0.617021 (-7650 4450);
PAINT AQUA (-7650 4450);
DISPLAY INVISIBLE (-7650 4450);
FORCEPROP 2 LAST BOM_COST SM_THERM
J 0
(-7650 4550);
DISPLAY 1.021277 (-7650 4550);
PAINT ORANGE (-7650 4550);
DISPLAY INVISIBLE (-7650 4550);
FORCEPROP 2 LAST CDS_SEC 1
J 0
(-7650 4500);
PAINT ORANGE (-7650 4500);
DISPLAY INVISIBLE (-7650 4500);
FORCEPROP 2 LAST SEC_TYPE 0402V
J 0
(-7650 4550);
DISPLAY 1.021277 (-7650 4550);
PAINT ORANGE (-7650 4550);
DISPLAY INVISIBLE (-7650 4550);
FORCEPROP 2 LAST SEC 1
J 0
(-7650 4550);
PAINT MONO (-7650 4550);
DISPLAY INVISIBLE (-7650 4550);
FORCEADD CAP_A..1
(-7700 3675);
FORCEPROP 1 LASTPIN (-7700 3575) $PN 2
J 0
(-7690 3555);
DISPLAY 0.617021 (-7690 3555);
PAINT ORANGE (-7690 3555);
FORCEPROP 1 LASTPIN (-7700 3775) $PN 1
J 0
(-7690 3755);
DISPLAY 0.617021 (-7690 3755);
PAINT ORANGE (-7690 3755);
FORCEPROP 1 LAST PACK_TYPE 0402V
J 0
(-7650 3475);
DISPLAY 0.617021 (-7650 3475);
PAINT SKYBLUE (-7650 3475);
FORCEPROP 1 LAST PART_NUMBER A36096-030
J 0
(-7650 3525);
DISPLAY 0.617021 (-7650 3525);
PAINT BLUE (-7650 3525);
FORCEPROP 1 LAST MATERIAL X7R
J 0
(-7650 3575);
DISPLAY 0.617021 (-7650 3575);
PAINT SKYBLUE (-7650 3575);
FORCEPROP 1 LAST LOCATION C9R14
J 0
(-7650 3775);
DISPLAY 0.617021 (-7650 3775);
PAINT AQUA (-7650 3775);
FORCEPROP 1 LAST VALUE 0.1UF
J 0
(-7650 3725);
DISPLAY 0.617021 (-7650 3725);
PAINT SKYBLUE (-7650 3725);
FORCEPROP 1 LAST TOLERANCE 10%
J 0
(-7650 3625);
DISPLAY 0.617021 (-7650 3625);
PAINT SKYBLUE (-7650 3625);
FORCEPROP 1 LAST VOLTAGE 16V
J 0
(-7650 3675);
DISPLAY 0.617021 (-7650 3675);
PAINT SKYBLUE (-7650 3675);
FORCEPROP 2 LAST CDS_LIB dev_discrete
J 0
(-7700 3675);
PAINT ORANGE (-7700 3675);
DISPLAY INVISIBLE (-7700 3675);
FORCEPROP 1 LAST PATH I41
J 0
(-7650 3825);
DISPLAY 0.978723 (-7650 3825);
PAINT WHITE (-7650 3825);
DISPLAY INVISIBLE (-7650 3825);
FORCEPROP 2 LAST ROOM TEMP_SENSORS
J 0
(-7650 3825);
DISPLAY 1.021277 (-7650 3825);
PAINT ORANGE (-7650 3825);
DISPLAY INVISIBLE (-7650 3825);
FORCEPROP 2 LAST CDS_LOCATION C9R14
J 0
(-7650 3775);
DISPLAY 0.617021 (-7650 3775);
PAINT AQUA (-7650 3775);
DISPLAY INVISIBLE (-7650 3775);
FORCEPROP 2 LAST BOM_COST SM_THERM
J 0
(-7650 3875);
DISPLAY 1.021277 (-7650 3875);
PAINT ORANGE (-7650 3875);
DISPLAY INVISIBLE (-7650 3875);
FORCEPROP 2 LAST CDS_SEC 1
J 0
(-7650 3825);
PAINT ORANGE (-7650 3825);
DISPLAY INVISIBLE (-7650 3825);
FORCEPROP 2 LAST SEC_TYPE 0402V
J 0
(-7650 3875);
DISPLAY 1.021277 (-7650 3875);
PAINT ORANGE (-7650 3875);
DISPLAY INVISIBLE (-7650 3875);
FORCEPROP 2 LAST SEC 1
J 0
(-7650 3875);
PAINT MONO (-7650 3875);
DISPLAY INVISIBLE (-7650 3875);
FORCEADD CAP_A..1
(-1425 2150);
FORCEPROP 1 LAST PACK_TYPE 0402V
J 0
(-1375 1950);
DISPLAY 0.617021 (-1375 1950);
PAINT SKYBLUE (-1375 1950);
FORCEPROP 1 LAST PART_NUMBER A36096-030
J 0
(-1375 2000);
DISPLAY 0.617021 (-1375 2000);
PAINT BLUE (-1375 2000);
FORCEPROP 1 LASTPIN (-1425 2050) $PN 2
J 0
(-1415 2030);
DISPLAY 0.617021 (-1415 2030);
PAINT ORANGE (-1415 2030);
FORCEPROP 1 LASTPIN (-1425 2250) $PN 1
J 0
(-1415 2230);
DISPLAY 0.617021 (-1415 2230);
PAINT ORANGE (-1415 2230);
FORCEPROP 1 LAST MATERIAL X7R
J 0
(-1375 2050);
DISPLAY 0.617021 (-1375 2050);
PAINT SKYBLUE (-1375 2050);
FORCEPROP 1 LAST VOLTAGE 16V
J 0
(-1375 2150);
DISPLAY 0.617021 (-1375 2150);
PAINT SKYBLUE (-1375 2150);
FORCEPROP 1 LAST TOLERANCE 10%
J 0
(-1375 2100);
DISPLAY 0.617021 (-1375 2100);
PAINT SKYBLUE (-1375 2100);
FORCEPROP 1 LAST VALUE 0.1UF
J 0
(-1375 2200);
DISPLAY 0.617021 (-1375 2200);
PAINT SKYBLUE (-1375 2200);
FORCEPROP 1 LAST LOCATION C9R13
J 0
(-1375 2250);
DISPLAY 0.617021 (-1375 2250);
PAINT AQUA (-1375 2250);
FORCEPROP 2 LAST CDS_LIB dev_discrete
J 0
(-1425 2150);
PAINT ORANGE (-1425 2150);
DISPLAY INVISIBLE (-1425 2150);
FORCEPROP 2 LAST CDS_LOCATION C9R13
J 0
(-1375 2250);
DISPLAY 0.617021 (-1375 2250);
PAINT AQUA (-1375 2250);
DISPLAY INVISIBLE (-1375 2250);
FORCEPROP 2 LAST CDS_SEC 1
J 0
(-1375 2300);
PAINT ORANGE (-1375 2300);
DISPLAY INVISIBLE (-1375 2300);
FORCEPROP 2 LAST ROOM TEMP_SENSORS
J 0
(-1375 2300);
DISPLAY 1.021277 (-1375 2300);
PAINT ORANGE (-1375 2300);
DISPLAY INVISIBLE (-1375 2300);
FORCEPROP 1 LAST PATH I42
J 0
(-1375 2300);
DISPLAY 0.978723 (-1375 2300);
PAINT WHITE (-1375 2300);
DISPLAY INVISIBLE (-1375 2300);
FORCEPROP 2 LAST SEC 1
J 0
(-1375 2350);
PAINT MONO (-1375 2350);
DISPLAY INVISIBLE (-1375 2350);
FORCEPROP 2 LAST SEC_TYPE 0402V
J 0
(-1375 2350);
DISPLAY 1.021277 (-1375 2350);
PAINT ORANGE (-1375 2350);
DISPLAY INVISIBLE (-1375 2350);
FORCEPROP 2 LAST BOM_COST SM_THERM
J 0
(-1375 2350);
DISPLAY 1.021277 (-1375 2350);
PAINT ORANGE (-1375 2350);
DISPLAY INVISIBLE (-1375 2350);
FORCEADD GND..1
(-7700 3350);
FORCEPROP 3 LASTPIN (-7700 3400) SIG_NAME GND\g
J 0
(-7690 3410);
DISPLAY 0.659574 (-7690 3410);
PAINT MONO (-7690 3410);
DISPLAY INVISIBLE (-7690 3410);
FORCEPROP 1 LAST HDL_POWER GND
J 0
(-7700 3500);
DISPLAY 0.872340 (-7700 3500);
PAINT GREEN (-7700 3500);
DISPLAY INVISIBLE (-7700 3500);
FORCEPROP 1 LAST BODY_TYPE PLUMBING
J 0
(-7745 3307);
DISPLAY 0.340426 (-7745 3307);
PAINT GREEN (-7745 3307);
DISPLAY INVISIBLE (-7745 3307);
FORCEPROP 2 LAST CDS_LIB mstr_symbols
J 0
(-7700 3350);
PAINT ORANGE (-7700 3350);
DISPLAY INVISIBLE (-7700 3350);
FORCEPROP 1 LAST VOLTAGE 0.0V
J 0
(-7745 3307);
DISPLAY 0.340426 (-7745 3307);
PAINT SKYBLUE (-7745 3307);
DISPLAY INVISIBLE (-7745 3307);
FORCEPROP 1 LAST SIZE 1B
J 0
(-7625 3300);
DISPLAY 0.872340 (-7625 3300);
PAINT AQUA (-7625 3300);
DISPLAY INVISIBLE (-7625 3300);
FORCEPROP 1 LAST PATH I45
J 0
(-7625 3350);
DISPLAY 0.872340 (-7625 3350);
PAINT AQUA (-7625 3350);
DISPLAY INVISIBLE (-7625 3350);
FORCEADD GND..1
(-1425 1825);
FORCEPROP 3 LASTPIN (-1425 1875) SIG_NAME GND\g
J 0
(-1415 1885);
DISPLAY 0.659574 (-1415 1885);
PAINT MONO (-1415 1885);
DISPLAY INVISIBLE (-1415 1885);
FORCEPROP 1 LAST BODY_TYPE PLUMBING
J 0
(-1470 1782);
DISPLAY 0.340426 (-1470 1782);
PAINT GREEN (-1470 1782);
DISPLAY INVISIBLE (-1470 1782);
FORCEPROP 1 LAST SIZE 1B
J 0
(-1350 1775);
DISPLAY 0.872340 (-1350 1775);
PAINT AQUA (-1350 1775);
DISPLAY INVISIBLE (-1350 1775);
FORCEPROP 1 LAST VOLTAGE 0.0V
J 0
(-1470 1782);
DISPLAY 0.340426 (-1470 1782);
PAINT SKYBLUE (-1470 1782);
DISPLAY INVISIBLE (-1470 1782);
FORCEPROP 1 LAST HDL_POWER GND
J 0
(-1425 1975);
DISPLAY 0.872340 (-1425 1975);
PAINT GREEN (-1425 1975);
DISPLAY INVISIBLE (-1425 1975);
FORCEPROP 1 LAST PATH I46
J 0
(-1350 1825);
DISPLAY 0.872340 (-1350 1825);
PAINT AQUA (-1350 1825);
DISPLAY INVISIBLE (-1350 1825);
FORCEPROP 2 LAST CDS_LIB mstr_symbols
J 0
(-1425 1825);
PAINT ORANGE (-1425 1825);
DISPLAY INVISIBLE (-1425 1825);
FORCEADD GND..1
(-7700 4100);
FORCEPROP 3 LASTPIN (-7700 4150) SIG_NAME GND\g
J 0
(-7690 4160);
DISPLAY 0.659574 (-7690 4160);
PAINT MONO (-7690 4160);
DISPLAY INVISIBLE (-7690 4160);
FORCEPROP 1 LAST BODY_TYPE PLUMBING
J 0
(-7745 4057);
DISPLAY 0.340426 (-7745 4057);
PAINT GREEN (-7745 4057);
DISPLAY INVISIBLE (-7745 4057);
FORCEPROP 1 LAST VOLTAGE 0.0V
J 0
(-7745 4057);
DISPLAY 0.340426 (-7745 4057);
PAINT SKYBLUE (-7745 4057);
DISPLAY INVISIBLE (-7745 4057);
FORCEPROP 1 LAST SIZE 1B
J 0
(-7625 4050);
DISPLAY 0.872340 (-7625 4050);
PAINT AQUA (-7625 4050);
DISPLAY INVISIBLE (-7625 4050);
FORCEPROP 1 LAST HDL_POWER GND
J 0
(-7700 4250);
DISPLAY 0.872340 (-7700 4250);
PAINT GREEN (-7700 4250);
DISPLAY INVISIBLE (-7700 4250);
FORCEPROP 2 LAST CDS_LIB mstr_symbols
J 0
(-7700 4100);
PAINT ORANGE (-7700 4100);
DISPLAY INVISIBLE (-7700 4100);
FORCEPROP 1 LAST PATH I47
J 0
(-7625 4100);
DISPLAY 0.872340 (-7625 4100);
PAINT AQUA (-7625 4100);
DISPLAY INVISIBLE (-7625 4100);
FORCEADD AT24C64..1
(-2700 1650);
FORCEPROP 2 LASTPIN (-3000 1500) $PN 7
J 2
(-3010 1510);
DISPLAY 0.617021 (-3010 1510);
PAINT ORANGE (-3010 1510);
FORCEPROP 1 LAST PART_NUMBER C47049-001
J 0
(-2950 1300);
DISPLAY 0.617021 (-2950 1300);
PAINT BLUE (-2950 1300);
FORCEPROP 2 LASTPIN (-3000 1700) $PN 2
J 2
(-3010 1710);
DISPLAY 0.617021 (-3010 1710);
PAINT ORANGE (-3010 1710);
FORCEPROP 2 LASTPIN (-3000 1650) $PN 1
J 2
(-3010 1660);
DISPLAY 0.617021 (-3010 1660);
PAINT ORANGE (-3010 1660);
FORCEPROP 2 LASTPIN (-3000 1550) $PN 6
J 2
(-3010 1560);
DISPLAY 0.617021 (-3010 1560);
PAINT ORANGE (-3010 1560);
FORCEPROP 2 LASTPIN (-3000 1750) $PN 3
J 2
(-3010 1760);
DISPLAY 0.617021 (-3010 1760);
PAINT ORANGE (-3010 1760);
FORCEPROP 1 LAST MATERIAL IC
J 0
(-2950 1950);
DISPLAY 0.617021 (-2950 1950);
PAINT SKYBLUE (-2950 1950);
FORCEPROP 1 LAST LOCATION U8D4
J 0
(-2950 2000);
DISPLAY 0.617021 (-2950 2000);
PAINT AQUA (-2950 2000);
FORCEPROP 1 LAST POWER_GROUP VCC=P3V3_STBY;GND=GND;
J 0
(-2950 1250);
DISPLAY 0.617021 (-2950 1250);
PAINT ORANGE (-2950 1250);
FORCEPROP 2 LASTPIN (-2400 1550) $PN 5
J 0
(-2390 1560);
DISPLAY 0.617021 (-2390 1560);
PAINT ORANGE (-2390 1560);
FORCEPROP 2 LAST CDS_LOCATION U8D4
J 0
(-2950 2000);
DISPLAY 0.617021 (-2950 2000);
PAINT AQUA (-2950 2000);
DISPLAY INVISIBLE (-2950 2000);
FORCEPROP 2 LAST CDS_LIB mstr_memory
J 0
(-2700 1650);
PAINT ORANGE (-2700 1650);
DISPLAY INVISIBLE (-2700 1650);
FORCEPROP 1 LAST PATH I49
J 0
(-2525 1950);
DISPLAY 0.957447 (-2525 1950);
PAINT PURPLE (-2525 1950);
DISPLAY INVISIBLE (-2525 1950);
FORCEPROP 2 LAST ROOM TEMP_SENSORS
J 0
(-2950 2050);
DISPLAY 1.021277 (-2950 2050);
PAINT ORANGE (-2950 2050);
DISPLAY INVISIBLE (-2950 2050);
FORCEPROP 1 LAST PACK_TYPE SOICLF
J 0
(-2950 2050);
DISPLAY 0.957447 (-2950 2050);
PAINT SKYBLUE (-2950 2050);
DISPLAY INVISIBLE (-2950 2050);
FORCEPROP 2 LAST SEC_TYPE SOICLF
J 0
(-2950 2050);
DISPLAY 1.021277 (-2950 2050);
PAINT ORANGE (-2950 2050);
DISPLAY INVISIBLE (-2950 2050);
FORCEPROP 2 LAST BOM_COST SM_THERM
J 0
(-2950 2100);
DISPLAY 1.021277 (-2950 2100);
PAINT ORANGE (-2950 2100);
DISPLAY INVISIBLE (-2950 2100);
FORCEPROP 2 LAST SEC 1
J 0
(-2950 2050);
DISPLAY 0.680851 (-2950 2050);
PAINT MONO (-2950 2050);
DISPLAY INVISIBLE (-2950 2050);
FORCEADD RES..1
(-5150 4450);
FORCEPROP 1 LAST WATTAGE 1/16W
J 2
(-5300 4400);
DISPLAY 0.617021 (-5300 4400);
PAINT SKYBLUE (-5300 4400);
FORCEPROP 1 LAST VALUE 49.9
J 2
(-5200 4400);
DISPLAY 0.617021 (-5200 4400);
PAINT SKYBLUE (-5200 4400);
FORCEPROP 1 LASTPIN (-5250 4450) $PN 1
J 0
(-5238 4462);
DISPLAY 0.617021 (-5238 4462);
PAINT ORANGE (-5238 4462);
FORCEPROP 1 LAST MATERIAL CHIP
J 0
(-5175 4400);
DISPLAY 0.617021 (-5175 4400);
PAINT SKYBLUE (-5175 4400);
FORCEPROP 1 LAST PART_NUMBER G21796-047
J 0
(-5200 4550);
DISPLAY 0.617021 (-5200 4550);
PAINT BLUE (-5200 4550);
FORCEPROP 1 LAST LOCATION R9B5
J 0
(-5200 4500);
DISPLAY 0.617021 (-5200 4500);
PAINT AQUA (-5200 4500);
FORCEPROP 1 LAST TOLERANCE 1%
J 0
(-5075 4400);
DISPLAY 0.617021 (-5075 4400);
PAINT SKYBLUE (-5075 4400);
FORCEPROP 1 LASTPIN (-5050 4450) $PN 2
J 0
(-5088 4462);
DISPLAY 0.617021 (-5088 4462);
PAINT ORANGE (-5088 4462);
FORCEPROP 1 LAST PACK_TYPE 0402
J 0
(-4975 4400);
DISPLAY 0.617021 (-4975 4400);
PAINT SKYBLUE (-4975 4400);
FORCEPROP 2 LAST CDS_LOCATION R9B5
J 0
(-5200 4500);
DISPLAY 0.617021 (-5200 4500);
PAINT AQUA (-5200 4500);
DISPLAY INVISIBLE (-5200 4500);
FORCEPROP 2 LAST CDS_LIB mstr_discrete
J 0
(-5150 4450);
PAINT ORANGE (-5150 4450);
DISPLAY INVISIBLE (-5150 4450);
FORCEPROP 2 LAST ROOM TEMP_SENSORS
J 0
(-5200 4600);
DISPLAY 1.021277 (-5200 4600);
PAINT ORANGE (-5200 4600);
DISPLAY INVISIBLE (-5200 4600);
FORCEPROP 1 LAST PATH I5
J 0
(-5200 4600);
DISPLAY 0.978723 (-5200 4600);
PAINT WHITE (-5200 4600);
DISPLAY INVISIBLE (-5200 4600);
FORCEPROP 0 LAST SEC 1
J 0
(-5200 4600);
DISPLAY 0.680851 (-5200 4600);
PAINT MONO (-5200 4600);
DISPLAY INVISIBLE (-5200 4600);
FORCEPROP 2 LAST SEC_TYPE 0402
J 0
(-5200 4650);
DISPLAY 1.021277 (-5200 4650);
PAINT ORANGE (-5200 4650);
DISPLAY INVISIBLE (-5200 4650);
FORCEPROP 2 LAST BOM_COST SM_THERM
J 0
(-5200 4650);
DISPLAY 1.021277 (-5200 4650);
PAINT ORANGE (-5200 4650);
DISPLAY INVISIBLE (-5200 4650);
FORCEADD RES..2
(-3500 1300);
FORCEPROP 1 LASTPIN (-3500 1200) $PN 2
J 0
(-3495 1210);
DISPLAY 0.617021 (-3495 1210);
PAINT ORANGE (-3495 1210);
FORCEPROP 1 LAST MATERIAL CHIP
J 0
(-3460 1225);
DISPLAY 0.617021 (-3460 1225);
PAINT SKYBLUE (-3460 1225);
FORCEPROP 1 LAST PACK_TYPE 0402
J 0
(-3460 1125);
DISPLAY 0.617021 (-3460 1125);
PAINT SKYBLUE (-3460 1125);
FORCEPROP 1 LASTPIN (-3500 1400) $PN 1
J 0
(-3495 1362);
DISPLAY 0.617021 (-3495 1362);
PAINT ORANGE (-3495 1362);
FORCEPROP 1 LAST TOLERANCE 1%
J 0
(-3455 1325);
DISPLAY 0.617021 (-3455 1325);
PAINT SKYBLUE (-3455 1325);
FORCEPROP 1 LAST WATTAGE 1/16W
J 0
(-3460 1275);
DISPLAY 0.617021 (-3460 1275);
PAINT SKYBLUE (-3460 1275);
FORCEPROP 1 LAST VALUE 1.00K
J 0
(-3455 1375);
DISPLAY 0.617021 (-3455 1375);
PAINT SKYBLUE (-3455 1375);
FORCEPROP 1 LAST PART_NUMBER G21796-026
J 0
(-3460 1175);
DISPLAY 0.617021 (-3460 1175);
PAINT BLUE (-3460 1175);
FORCEPROP 1 LAST LOCATION R8D27
J 0
(-3455 1425);
DISPLAY 0.617021 (-3455 1425);
PAINT AQUA (-3455 1425);
FORCEPROP 2 LAST CDS_LIB mstr_discrete
J 0
(-3500 1300);
PAINT ORANGE (-3500 1300);
DISPLAY INVISIBLE (-3500 1300);
FORCEPROP 0 LAST SEC 1
J 0
(-3450 1475);
DISPLAY 0.680851 (-3450 1475);
PAINT MONO (-3450 1475);
DISPLAY INVISIBLE (-3450 1475);
FORCEPROP 2 LAST CDS_LOCATION R8D27
J 0
(-3455 1425);
DISPLAY 0.617021 (-3455 1425);
PAINT AQUA (-3455 1425);
DISPLAY INVISIBLE (-3455 1425);
FORCEPROP 1 LAST PATH I50
J 0
(-3450 1475);
DISPLAY 0.978723 (-3450 1475);
PAINT WHITE (-3450 1475);
DISPLAY INVISIBLE (-3450 1475);
FORCEPROP 2 LAST ROOM TEMP_SENSORS
J 0
(-3450 1475);
DISPLAY 1.021277 (-3450 1475);
PAINT ORANGE (-3450 1475);
DISPLAY INVISIBLE (-3450 1475);
FORCEPROP 2 LAST BOM_COST SM_THERM
J 0
(-3450 1525);
DISPLAY 1.021277 (-3450 1525);
PAINT ORANGE (-3450 1525);
DISPLAY INVISIBLE (-3450 1525);
FORCEPROP 2 LAST SEC_TYPE 0402
J 0
(-3450 1525);
DISPLAY 1.021277 (-3450 1525);
PAINT ORANGE (-3450 1525);
DISPLAY INVISIBLE (-3450 1525);
FORCEADD GND..1
(-3500 1050);
FORCEPROP 3 LASTPIN (-3500 1100) SIG_NAME GND\g
J 0
(-3490 1110);
DISPLAY 0.659574 (-3490 1110);
PAINT MONO (-3490 1110);
DISPLAY INVISIBLE (-3490 1110);
FORCEPROP 1 LAST BODY_TYPE PLUMBING
J 0
(-3545 1007);
DISPLAY 0.340426 (-3545 1007);
PAINT GREEN (-3545 1007);
DISPLAY INVISIBLE (-3545 1007);
FORCEPROP 1 LAST VOLTAGE 0.0V
J 0
(-3545 1007);
DISPLAY 0.340426 (-3545 1007);
PAINT SKYBLUE (-3545 1007);
DISPLAY INVISIBLE (-3545 1007);
FORCEPROP 1 LAST SIZE 1B
J 0
(-3425 1000);
DISPLAY 0.872340 (-3425 1000);
PAINT AQUA (-3425 1000);
DISPLAY INVISIBLE (-3425 1000);
FORCEPROP 2 LAST CDS_LIB mstr_symbols
J 0
(-3500 1050);
PAINT ORANGE (-3500 1050);
DISPLAY INVISIBLE (-3500 1050);
FORCEPROP 1 LAST HDL_POWER GND
J 0
(-3500 1200);
DISPLAY 0.872340 (-3500 1200);
PAINT GREEN (-3500 1200);
DISPLAY INVISIBLE (-3500 1200);
FORCEPROP 1 LAST PATH I52
J 0
(-3425 1050);
DISPLAY 0.872340 (-3425 1050);
PAINT AQUA (-3425 1050);
DISPLAY INVISIBLE (-3425 1050);
FORCEADD GND..1
(-3075 1050);
FORCEPROP 3 LASTPIN (-3075 1100) SIG_NAME GND\g
J 0
(-3065 1110);
DISPLAY 0.659574 (-3065 1110);
PAINT MONO (-3065 1110);
DISPLAY INVISIBLE (-3065 1110);
FORCEPROP 1 LAST BODY_TYPE PLUMBING
J 0
(-3120 1007);
DISPLAY 0.340426 (-3120 1007);
PAINT GREEN (-3120 1007);
DISPLAY INVISIBLE (-3120 1007);
FORCEPROP 1 LAST VOLTAGE 0.0V
J 0
(-3120 1007);
DISPLAY 0.340426 (-3120 1007);
PAINT SKYBLUE (-3120 1007);
DISPLAY INVISIBLE (-3120 1007);
FORCEPROP 1 LAST HDL_POWER GND
J 0
(-3075 1200);
DISPLAY 0.872340 (-3075 1200);
PAINT GREEN (-3075 1200);
DISPLAY INVISIBLE (-3075 1200);
FORCEPROP 2 LAST CDS_LIB mstr_symbols
J 0
(-3075 1050);
PAINT ORANGE (-3075 1050);
DISPLAY INVISIBLE (-3075 1050);
FORCEPROP 1 LAST SIZE 1B
J 0
(-3000 1000);
DISPLAY 0.872340 (-3000 1000);
PAINT AQUA (-3000 1000);
DISPLAY INVISIBLE (-3000 1000);
FORCEPROP 1 LAST PATH I55
J 0
(-3000 1050);
DISPLAY 0.872340 (-3000 1050);
PAINT AQUA (-3000 1050);
DISPLAY INVISIBLE (-3000 1050);
FORCEADD P3V3_STBY..1
(-7700 4650);
FORCEPROP 3 LASTPIN (-7700 4600) SIG_NAME P3V3_STBY\g
J 0
(-7690 4610);
DISPLAY 0.659574 (-7690 4610);
PAINT MONO (-7690 4610);
DISPLAY INVISIBLE (-7690 4610);
FORCEPROP 1 LAST HDL_POWER P3V3_STBY
J 0
(-8000 4525);
DISPLAY 0.872340 (-8000 4525);
PAINT ORANGE (-8000 4525);
DISPLAY INVISIBLE (-8000 4525);
FORCEPROP 1 LAST BODY_TYPE PLUMBING
J 0
(-7745 4607);
DISPLAY 0.340426 (-7745 4607);
PAINT GREEN (-7745 4607);
DISPLAY INVISIBLE (-7745 4607);
FORCEPROP 1 LAST VOLTAGE 3.3V
J 0
(-7745 4607);
DISPLAY 0.340426 (-7745 4607);
PAINT SKYBLUE (-7745 4607);
DISPLAY INVISIBLE (-7745 4607);
FORCEPROP 2 LAST CDS_LIB mstr_symbols
J 0
(-7700 4650);
PAINT ORANGE (-7700 4650);
DISPLAY INVISIBLE (-7700 4650);
FORCEPROP 1 LAST SIZE 1B
J 0
(-7655 4672);
DISPLAY 0.340426 (-7655 4672);
PAINT GREEN (-7655 4672);
DISPLAY INVISIBLE (-7655 4672);
FORCEPROP 1 LAST PATH I56
J 0
(-7655 4652);
DISPLAY 0.340426 (-7655 4652);
PAINT GREEN (-7655 4652);
DISPLAY INVISIBLE (-7655 4652);
FORCEADD P3V3_STBY..1
(-7700 3950);
FORCEPROP 3 LASTPIN (-7700 3900) SIG_NAME P3V3_STBY\g
J 0
(-7690 3910);
DISPLAY 0.659574 (-7690 3910);
PAINT MONO (-7690 3910);
DISPLAY INVISIBLE (-7690 3910);
FORCEPROP 1 LAST HDL_POWER P3V3_STBY
J 0
(-8000 3825);
DISPLAY 0.872340 (-8000 3825);
PAINT ORANGE (-8000 3825);
DISPLAY INVISIBLE (-8000 3825);
FORCEPROP 1 LAST BODY_TYPE PLUMBING
J 0
(-7745 3907);
DISPLAY 0.340426 (-7745 3907);
PAINT GREEN (-7745 3907);
DISPLAY INVISIBLE (-7745 3907);
FORCEPROP 2 LAST CDS_LIB mstr_symbols
J 0
(-7700 3950);
PAINT ORANGE (-7700 3950);
DISPLAY INVISIBLE (-7700 3950);
FORCEPROP 1 LAST VOLTAGE 3.3V
J 0
(-7745 3907);
DISPLAY 0.340426 (-7745 3907);
PAINT SKYBLUE (-7745 3907);
DISPLAY INVISIBLE (-7745 3907);
FORCEPROP 1 LAST SIZE 1B
J 0
(-7655 3972);
DISPLAY 0.340426 (-7655 3972);
PAINT GREEN (-7655 3972);
DISPLAY INVISIBLE (-7655 3972);
FORCEPROP 1 LAST PATH I57
J 0
(-7655 3952);
DISPLAY 0.340426 (-7655 3952);
PAINT GREEN (-7655 3952);
DISPLAY INVISIBLE (-7655 3952);
FORCEADD RES..1
(-6725 1450);
FORCEPROP 1 LASTPIN (-6825 1450) $PN 1
J 0
(-6813 1462);
DISPLAY 0.617021 (-6813 1462);
PAINT ORANGE (-6813 1462);
FORCEPROP 1 LAST VALUE 20.0
J 2
(-6775 1400);
DISPLAY 0.617021 (-6775 1400);
PAINT SKYBLUE (-6775 1400);
FORCEPROP 1 LASTPIN (-6625 1450) $PN 2
J 0
(-6663 1462);
DISPLAY 0.617021 (-6663 1462);
PAINT ORANGE (-6663 1462);
FORCEPROP 1 LAST LOCATION R9G15
J 0
(-6750 1550);
DISPLAY 0.617021 (-6750 1550);
PAINT AQUA (-6750 1550);
FORCEPROP 1 LAST TOLERANCE 1%
J 0
(-6650 1400);
DISPLAY 0.617021 (-6650 1400);
PAINT SKYBLUE (-6650 1400);
FORCEPROP 1 LAST MATERIAL CHIP
J 0
(-6575 1400);
DISPLAY 0.617021 (-6575 1400);
PAINT SKYBLUE (-6575 1400);
FORCEPROP 1 LAST PART_NUMBER G21796-173
J 0
(-6475 1400);
DISPLAY 0.617021 (-6475 1400);
PAINT BLUE (-6475 1400);
FORCEPROP 1 LAST WATTAGE 1/16W
J 2
(-6850 1400);
DISPLAY 0.617021 (-6850 1400);
PAINT SKYBLUE (-6850 1400);
DISPLAY INVISIBLE (-6850 1400);
FORCEPROP 2 LAST CDS_LIB mstr_discrete
J 0
(-6725 1450);
PAINT MONO (-6725 1450);
DISPLAY INVISIBLE (-6725 1450);
FORCEPROP 1 LAST PATH I58
J 0
(-6775 1600);
DISPLAY 0.978723 (-6775 1600);
PAINT WHITE (-6775 1600);
DISPLAY INVISIBLE (-6775 1600);
FORCEPROP 2 LAST CDS_LOCATION R9G15
J 0
(-6750 1550);
DISPLAY 0.617021 (-6750 1550);
PAINT AQUA (-6750 1550);
DISPLAY INVISIBLE (-6750 1550);
FORCEPROP 2 LAST $SEC 1
J 0
(-6775 1650);
PAINT MONO (-6775 1650);
DISPLAY INVISIBLE (-6775 1650);
FORCEPROP 2 LAST CDS_SEC 1
J 0
(-6775 1650);
PAINT MONO (-6775 1650);
DISPLAY INVISIBLE (-6775 1650);
FORCEPROP 1 LAST PACK_TYPE 0402
J 0
(-6575 1400);
DISPLAY 0.617021 (-6575 1400);
PAINT SKYBLUE (-6575 1400);
DISPLAY INVISIBLE (-6575 1400);
FORCEPROP 0 LAST ROOM SMBUS
J 0
(-6475 1500);
DISPLAY 1.021277 (-6475 1500);
PAINT ORANGE (-6475 1500);
DISPLAY INVISIBLE (-6475 1500);
FORCEPROP 0 LAST SKU B
J 0
(-6475 1500);
DISPLAY 1.021277 (-6475 1500);
PAINT ORANGE (-6475 1500);
DISPLAY INVISIBLE (-6475 1500);
FORCEPROP 0 LAST BOM_COST SM_CONTROLLER
J 0
(-6475 1600);
DISPLAY 1.021277 (-6475 1600);
PAINT ORANGE (-6475 1600);
DISPLAY INVISIBLE (-6475 1600);
FORCEADD RES..1
(-5150 4775);
FORCEPROP 1 LAST VALUE 49.9
J 2
(-5175 4675);
DISPLAY 0.617021 (-5175 4675);
PAINT SKYBLUE (-5175 4675);
FORCEPROP 1 LAST WATTAGE 1/16W
J 2
(-5175 4625);
DISPLAY 0.617021 (-5175 4625);
PAINT SKYBLUE (-5175 4625);
FORCEPROP 1 LASTPIN (-5250 4775) $PN 1
J 0
(-5238 4787);
DISPLAY 0.617021 (-5238 4787);
PAINT ORANGE (-5238 4787);
FORCEPROP 1 LAST MATERIAL CHIP
J 0
(-5150 4625);
DISPLAY 0.617021 (-5150 4625);
PAINT SKYBLUE (-5150 4625);
FORCEPROP 1 LAST TOLERANCE 1%
J 0
(-5150 4675);
DISPLAY 0.617021 (-5150 4675);
PAINT SKYBLUE (-5150 4675);
FORCEPROP 1 LAST PART_NUMBER G21796-047
J 0
(-5200 4875);
DISPLAY 0.617021 (-5200 4875);
PAINT BLUE (-5200 4875);
FORCEPROP 1 LAST LOCATION R9B4
J 0
(-5200 4825);
DISPLAY 0.617021 (-5200 4825);
PAINT AQUA (-5200 4825);
FORCEPROP 1 LASTPIN (-5050 4775) $PN 2
J 0
(-5088 4787);
DISPLAY 0.617021 (-5088 4787);
PAINT ORANGE (-5088 4787);
FORCEPROP 1 LAST PACK_TYPE 0402
J 0
(-4900 4625);
DISPLAY 0.617021 (-4900 4625);
PAINT SKYBLUE (-4900 4625);
FORCEPROP 2 LAST CDS_LIB mstr_discrete
J 0
(-5150 4775);
PAINT ORANGE (-5150 4775);
DISPLAY INVISIBLE (-5150 4775);
FORCEPROP 2 LAST CDS_LOCATION R9B4
J 0
(-5200 4825);
DISPLAY 0.617021 (-5200 4825);
PAINT AQUA (-5200 4825);
DISPLAY INVISIBLE (-5200 4825);
FORCEPROP 2 LAST ROOM TEMP_SENSORS
J 0
(-5200 4925);
DISPLAY 1.021277 (-5200 4925);
PAINT ORANGE (-5200 4925);
DISPLAY INVISIBLE (-5200 4925);
FORCEPROP 1 LAST PATH I6
J 0
(-5200 4925);
DISPLAY 0.978723 (-5200 4925);
PAINT WHITE (-5200 4925);
DISPLAY INVISIBLE (-5200 4925);
FORCEPROP 0 LAST SEC 1
J 0
(-5200 4925);
DISPLAY 0.680851 (-5200 4925);
PAINT MONO (-5200 4925);
DISPLAY INVISIBLE (-5200 4925);
FORCEPROP 2 LAST BOM_COST SM_THERM
J 0
(-5200 4975);
DISPLAY 1.021277 (-5200 4975);
PAINT ORANGE (-5200 4975);
DISPLAY INVISIBLE (-5200 4975);
FORCEPROP 2 LAST SEC_TYPE 0402
J 0
(-5200 4975);
DISPLAY 1.021277 (-5200 4975);
PAINT ORANGE (-5200 4975);
DISPLAY INVISIBLE (-5200 4975);
FORCEADD OFFPAGE..3
(-5750 1450);
FORCEPROP 2 LAST $XR0 167 
J 0
(-5536 1450);
DISPLAY 0.638298 (-5536 1450);
PAINT MONO (-5536 1450);
FORCEPROP 2 LAST $XR1 184 
J 0
(-5416 1450);
DISPLAY 0.638298 (-5416 1450);
PAINT MONO (-5416 1450);
FORCEPROP 2 LAST $XR2 191 
J 0
(-5296 1450);
DISPLAY 0.638298 (-5296 1450);
PAINT MONO (-5296 1450);
FORCEPROP 1 LAST COMMENT_BODY TRUE
J 0
(-5800 1350);
DISPLAY 0.872340 (-5800 1350);
PAINT GREEN (-5800 1350);
DISPLAY INVISIBLE (-5800 1350);
FORCEPROP 2 LAST CDS_LIB mstr_standard
J 0
(-5750 1450);
PAINT MONO (-5750 1450);
DISPLAY INVISIBLE (-5750 1450);
FORCEPROP 2 LAST PATH I60
J 0
(-5700 1525);
DISPLAY 1.021277 (-5700 1525);
PAINT ORANGE (-5700 1525);
DISPLAY INVISIBLE (-5700 1525);
FORCEPROP 1 LAST OFFPAGE TRUE
J 0
(-5425 1325);
DISPLAY 0.872340 (-5425 1325);
PAINT GREEN (-5425 1325);
DISPLAY INVISIBLE (-5425 1325);
FORCEADD OFFPAGE..6
(-7525 1450);
FORCEPROP 2 LAST $XR0 144 
J 0
(-7805 1450);
DISPLAY 0.638298 (-7805 1450);
PAINT MONO (-7805 1450);
FORCEPROP 1 LAST COMMENT_BODY TRUE
J 0
(-7425 1375);
DISPLAY 0.872340 (-7425 1375);
PAINT GREEN (-7425 1375);
DISPLAY INVISIBLE (-7425 1375);
FORCEPROP 2 LAST CDS_LIB mstr_standard
J 0
(-7525 1450);
PAINT MONO (-7525 1450);
DISPLAY INVISIBLE (-7525 1450);
FORCEPROP 1 LAST OFFPAGE TRUE
J 0
(-7200 1325);
DISPLAY 0.872340 (-7200 1325);
PAINT GREEN (-7200 1325);
DISPLAY INVISIBLE (-7200 1325);
FORCEPROP 2 LAST PATH I61
J 0
(-7475 1525);
DISPLAY 1.021277 (-7475 1525);
PAINT ORANGE (-7475 1525);
DISPLAY INVISIBLE (-7475 1525);
FORCEADD OFFPAGE..1
(-7525 1325);
FORCEPROP 2 LAST $XR0 144 
J 0
(-7777 1325);
DISPLAY 0.638298 (-7777 1325);
PAINT MONO (-7777 1325);
FORCEPROP 2 LAST CDS_LIB mstr_standard
J 0
(-7525 1325);
PAINT MONO (-7525 1325);
DISPLAY INVISIBLE (-7525 1325);
FORCEPROP 2 LAST PATH I62
J 0
(-7475 1400);
DISPLAY 1.021277 (-7475 1400);
PAINT ORANGE (-7475 1400);
DISPLAY INVISIBLE (-7475 1400);
FORCEPROP 1 LAST COMMENT_BODY TRUE
J 0
(-7400 1225);
DISPLAY 0.872340 (-7400 1225);
PAINT GREEN (-7400 1225);
DISPLAY INVISIBLE (-7400 1225);
FORCEPROP 1 LAST OFFPAGE TRUE
J 0
(-7200 1200);
DISPLAY 0.872340 (-7200 1200);
PAINT GREEN (-7200 1200);
DISPLAY INVISIBLE (-7200 1200);
FORCEADD OFFPAGE..2
(-5750 1325);
FORCEPROP 2 LAST $XR0 167 
J 0
(-5561 1325);
DISPLAY 0.638298 (-5561 1325);
PAINT MONO (-5561 1325);
FORCEPROP 2 LAST $XR1 184 
J 0
(-5441 1325);
DISPLAY 0.638298 (-5441 1325);
PAINT MONO (-5441 1325);
FORCEPROP 2 LAST $XR2 191 
J 0
(-5321 1325);
DISPLAY 0.638298 (-5321 1325);
PAINT MONO (-5321 1325);
FORCEPROP 1 LAST COMMENT_BODY TRUE
J 0
(-5795 1230);
DISPLAY 0.872340 (-5795 1230);
PAINT GREEN (-5795 1230);
DISPLAY INVISIBLE (-5795 1230);
FORCEPROP 2 LAST CDS_LIB mstr_standard
J 0
(-5750 1325);
PAINT MONO (-5750 1325);
DISPLAY INVISIBLE (-5750 1325);
FORCEPROP 2 LAST PATH I63
J 0
(-5700 1400);
DISPLAY 1.021277 (-5700 1400);
PAINT ORANGE (-5700 1400);
DISPLAY INVISIBLE (-5700 1400);
FORCEPROP 1 LAST OFFPAGE TRUE
J 0
(-5425 1200);
DISPLAY 0.872340 (-5425 1200);
PAINT GREEN (-5425 1200);
DISPLAY INVISIBLE (-5425 1200);
FORCEADD OFFPAGE..3
(-5750 1150);
FORCEPROP 2 LAST $XR0 167 
J 0
(-5536 1150);
DISPLAY 0.638298 (-5536 1150);
PAINT MONO (-5536 1150);
FORCEPROP 2 LAST $XR1 184 
J 0
(-5416 1150);
DISPLAY 0.638298 (-5416 1150);
PAINT MONO (-5416 1150);
FORCEPROP 2 LAST $XR2 191 
J 0
(-5296 1150);
DISPLAY 0.638298 (-5296 1150);
PAINT MONO (-5296 1150);
FORCEPROP 1 LAST COMMENT_BODY TRUE
J 0
(-5800 1050);
DISPLAY 0.872340 (-5800 1050);
PAINT GREEN (-5800 1050);
DISPLAY INVISIBLE (-5800 1050);
FORCEPROP 2 LAST CDS_LIB mstr_standard
J 0
(-5750 1150);
PAINT MONO (-5750 1150);
DISPLAY INVISIBLE (-5750 1150);
FORCEPROP 2 LAST PATH I64
J 0
(-5550 1225);
DISPLAY 1.021277 (-5550 1225);
PAINT ORANGE (-5550 1225);
DISPLAY INVISIBLE (-5550 1225);
FORCEPROP 1 LAST OFFPAGE TRUE
J 0
(-5425 1025);
DISPLAY 0.872340 (-5425 1025);
PAINT GREEN (-5425 1025);
DISPLAY INVISIBLE (-5425 1025);
FORCEADD OFFPAGE..2
(-5750 1025);
FORCEPROP 2 LAST $XR0 167 
J 0
(-5561 1025);
DISPLAY 0.638298 (-5561 1025);
PAINT MONO (-5561 1025);
FORCEPROP 2 LAST $XR1 184 
J 0
(-5441 1025);
DISPLAY 0.638298 (-5441 1025);
PAINT MONO (-5441 1025);
FORCEPROP 2 LAST $XR2 191 
J 0
(-5321 1025);
DISPLAY 0.638298 (-5321 1025);
PAINT MONO (-5321 1025);
FORCEPROP 1 LAST COMMENT_BODY TRUE
J 0
(-5795 930);
DISPLAY 0.872340 (-5795 930);
PAINT GREEN (-5795 930);
DISPLAY INVISIBLE (-5795 930);
FORCEPROP 1 LAST OFFPAGE TRUE
J 0
(-5425 900);
DISPLAY 0.872340 (-5425 900);
PAINT GREEN (-5425 900);
DISPLAY INVISIBLE (-5425 900);
FORCEPROP 2 LAST CDS_LIB mstr_standard
J 0
(-5750 1025);
PAINT MONO (-5750 1025);
DISPLAY INVISIBLE (-5750 1025);
FORCEPROP 2 LAST PATH I65
J 0
(-5575 1100);
DISPLAY 1.021277 (-5575 1100);
PAINT ORANGE (-5575 1100);
DISPLAY INVISIBLE (-5575 1100);
FORCEADD OFFPAGE..6
(-7525 1150);
FORCEPROP 2 LAST $XR0 138 
J 0
(-7805 1150);
DISPLAY 0.638298 (-7805 1150);
PAINT MONO (-7805 1150);
FORCEPROP 2 LAST $XR1 165 
J 0
(-7925 1150);
DISPLAY 0.638298 (-7925 1150);
PAINT MONO (-7925 1150);
FORCEPROP 1 LAST COMMENT_BODY TRUE
J 0
(-7425 1075);
DISPLAY 0.872340 (-7425 1075);
PAINT GREEN (-7425 1075);
DISPLAY INVISIBLE (-7425 1075);
FORCEPROP 2 LAST CDS_LIB mstr_standard
J 0
(-7525 1150);
PAINT MONO (-7525 1150);
DISPLAY INVISIBLE (-7525 1150);
FORCEPROP 2 LAST PATH I67
J 0
(-7475 1225);
DISPLAY 1.021277 (-7475 1225);
PAINT ORANGE (-7475 1225);
DISPLAY INVISIBLE (-7475 1225);
FORCEPROP 1 LAST OFFPAGE TRUE
J 0
(-7200 1025);
DISPLAY 0.872340 (-7200 1025);
PAINT GREEN (-7200 1025);
DISPLAY INVISIBLE (-7200 1025);
FORCEADD OFFPAGE..1
(-7525 1025);
FORCEPROP 2 LAST $XR0 138 
J 0
(-7777 1025);
DISPLAY 0.638298 (-7777 1025);
PAINT MONO (-7777 1025);
FORCEPROP 2 LAST $XR1 165 
J 0
(-7897 1025);
DISPLAY 0.638298 (-7897 1025);
PAINT MONO (-7897 1025);
FORCEPROP 1 LAST COMMENT_BODY TRUE
J 0
(-7400 925);
DISPLAY 0.872340 (-7400 925);
PAINT GREEN (-7400 925);
DISPLAY INVISIBLE (-7400 925);
FORCEPROP 1 LAST OFFPAGE TRUE
J 0
(-7200 900);
DISPLAY 0.872340 (-7200 900);
PAINT GREEN (-7200 900);
DISPLAY INVISIBLE (-7200 900);
FORCEPROP 2 LAST CDS_LIB mstr_standard
J 0
(-7525 1025);
PAINT MONO (-7525 1025);
DISPLAY INVISIBLE (-7525 1025);
FORCEPROP 2 LAST PATH I69
J 0
(-7475 1100);
DISPLAY 1.021277 (-7475 1100);
PAINT ORANGE (-7475 1100);
DISPLAY INVISIBLE (-7475 1100);
FORCEADD CAP..1
(-4850 4625);
FORCEPROP 1 LASTPIN (-4850 4525) $PN 2
J 0
(-4840 4505);
DISPLAY 0.617021 (-4840 4505);
PAINT ORANGE (-4840 4505);
FORCEPROP 1 LAST TOLERANCE 5%
J 0
(-4800 4575);
DISPLAY 0.617021 (-4800 4575);
PAINT SKYBLUE (-4800 4575);
FORCEPROP 1 LAST MATERIAL EMPTY
J 0
(-4775 4500);
DISPLAY 0.617021 (-4775 4500);
PAINT RED (-4775 4500);
FORCEPROP 1 LAST PACK_TYPE 0402LF
J 0
(-4800 4425);
DISPLAY 0.617021 (-4800 4425);
PAINT SKYBLUE (-4800 4425);
FORCEPROP 1 LAST PART_NUMBER A36095-025
R 1
J 0
(-4625 4525);
DISPLAY 0.617021 (-4625 4525);
PAINT BLUE (-4625 4525);
FORCEPROP 1 LASTPIN (-4850 4725) $PN 1
J 0
(-4840 4705);
DISPLAY 0.617021 (-4840 4705);
PAINT ORANGE (-4840 4705);
FORCEPROP 1 LAST VOLTAGE 50V
J 0
(-4800 4625);
DISPLAY 0.617021 (-4800 4625);
PAINT SKYBLUE (-4800 4625);
FORCEPROP 1 LAST VALUE 47.0PF
J 0
(-4800 4675);
DISPLAY 0.617021 (-4800 4675);
PAINT SKYBLUE (-4800 4675);
FORCEPROP 1 LAST LOCATION C1M4
J 0
(-4800 4725);
DISPLAY 0.617021 (-4800 4725);
PAINT AQUA (-4800 4725);
FORCEPROP 2 LAST CDS_LIB mstr_discrete
J 0
(-4850 4625);
PAINT ORANGE (-4850 4625);
DISPLAY INVISIBLE (-4850 4625);
FORCEPROP 2 LAST CDS_LOCATION C1M4
J 0
(-4800 4725);
DISPLAY 0.617021 (-4800 4725);
PAINT AQUA (-4800 4725);
DISPLAY INVISIBLE (-4800 4725);
FORCEPROP 2 LAST ROOM TEMP_SENSORS
J 0
(-4800 4775);
DISPLAY 1.021277 (-4800 4775);
PAINT ORANGE (-4800 4775);
DISPLAY INVISIBLE (-4800 4775);
FORCEPROP 1 LAST PATH I7
J 0
(-4800 4775);
DISPLAY 0.978723 (-4800 4775);
PAINT WHITE (-4800 4775);
DISPLAY INVISIBLE (-4800 4775);
FORCEPROP 0 LAST SEC 1
J 0
(-4800 4775);
DISPLAY 0.680851 (-4800 4775);
PAINT MONO (-4800 4775);
DISPLAY INVISIBLE (-4800 4775);
FORCEPROP 2 LAST BOM_COST SM_THERM
J 0
(-4800 4825);
DISPLAY 1.021277 (-4800 4825);
PAINT ORANGE (-4800 4825);
DISPLAY INVISIBLE (-4800 4825);
FORCEPROP 2 LAST SEC_TYPE 0402LF
J 0
(-4800 4825);
DISPLAY 1.021277 (-4800 4825);
PAINT ORANGE (-4800 4825);
DISPLAY INVISIBLE (-4800 4825);
FORCEADD RES..2
(-3350 1975);
FORCEPROP 1 LASTPIN (-3350 1875) $PN 2
J 0
(-3345 1885);
DISPLAY 0.617021 (-3345 1885);
PAINT ORANGE (-3345 1885);
FORCEPROP 1 LAST TOLERANCE 1%
J 0
(-3305 2000);
DISPLAY 0.617021 (-3305 2000);
PAINT SKYBLUE (-3305 2000);
FORCEPROP 1 LAST PACK_TYPE 0402
J 0
(-3310 1800);
DISPLAY 0.617021 (-3310 1800);
PAINT SKYBLUE (-3310 1800);
FORCEPROP 1 LAST MATERIAL CHIP
J 0
(-3310 1900);
DISPLAY 0.617021 (-3310 1900);
PAINT SKYBLUE (-3310 1900);
FORCEPROP 1 LAST WATTAGE 1/16W
J 0
(-3310 1950);
DISPLAY 0.617021 (-3310 1950);
PAINT SKYBLUE (-3310 1950);
FORCEPROP 1 LAST PART_NUMBER G21796-026
J 0
(-3310 1850);
DISPLAY 0.617021 (-3310 1850);
PAINT BLUE (-3310 1850);
FORCEPROP 1 LASTPIN (-3350 2075) $PN 1
J 0
(-3345 2037);
DISPLAY 0.617021 (-3345 2037);
PAINT ORANGE (-3345 2037);
FORCEPROP 1 LAST LOCATION R8D28
J 0
(-3305 2100);
DISPLAY 0.617021 (-3305 2100);
PAINT AQUA (-3305 2100);
FORCEPROP 1 LAST VALUE 1.00K
J 0
(-3305 2050);
DISPLAY 0.617021 (-3305 2050);
PAINT SKYBLUE (-3305 2050);
FORCEPROP 2 LAST CDS_LIB mstr_discrete
J 0
(-3350 1975);
PAINT ORANGE (-3350 1975);
DISPLAY INVISIBLE (-3350 1975);
FORCEPROP 2 LAST SEC_TYPE 0402
J 0
(-3300 2200);
DISPLAY 1.021277 (-3300 2200);
PAINT ORANGE (-3300 2200);
DISPLAY INVISIBLE (-3300 2200);
FORCEPROP 2 LAST BOM_COST SM_THERM
J 0
(-3300 2200);
DISPLAY 1.021277 (-3300 2200);
PAINT ORANGE (-3300 2200);
DISPLAY INVISIBLE (-3300 2200);
FORCEPROP 0 LAST SEC 1
J 0
(-3300 2150);
DISPLAY 0.680851 (-3300 2150);
PAINT MONO (-3300 2150);
DISPLAY INVISIBLE (-3300 2150);
FORCEPROP 2 LAST CDS_LOCATION R8D28
J 0
(-3305 2100);
DISPLAY 0.617021 (-3305 2100);
PAINT AQUA (-3305 2100);
DISPLAY INVISIBLE (-3305 2100);
FORCEPROP 1 LAST PATH I70
J 0
(-3300 2150);
DISPLAY 0.978723 (-3300 2150);
PAINT WHITE (-3300 2150);
DISPLAY INVISIBLE (-3300 2150);
FORCEPROP 2 LAST ROOM TEMP_SENSORS
J 0
(-3300 2150);
DISPLAY 1.021277 (-3300 2150);
PAINT ORANGE (-3300 2150);
DISPLAY INVISIBLE (-3300 2150);
FORCEADD P3V3_STBY..1
(-3350 2200);
FORCEPROP 3 LASTPIN (-3350 2150) SIG_NAME P3V3_STBY\g
J 0
(-3340 2160);
DISPLAY 0.659574 (-3340 2160);
PAINT MONO (-3340 2160);
DISPLAY INVISIBLE (-3340 2160);
FORCEPROP 1 LAST HDL_POWER P3V3_STBY
J 0
(-3650 2075);
DISPLAY 0.872340 (-3650 2075);
PAINT ORANGE (-3650 2075);
DISPLAY INVISIBLE (-3650 2075);
FORCEPROP 2 LAST CDS_LIB mstr_symbols
J 0
(-3350 2200);
PAINT MONO (-3350 2200);
DISPLAY INVISIBLE (-3350 2200);
FORCEPROP 1 LAST VOLTAGE 3.3V
J 0
(-3395 2157);
DISPLAY 0.340426 (-3395 2157);
PAINT SKYBLUE (-3395 2157);
DISPLAY INVISIBLE (-3395 2157);
FORCEPROP 1 LAST BODY_TYPE PLUMBING
J 0
(-3395 2157);
DISPLAY 0.340426 (-3395 2157);
PAINT GREEN (-3395 2157);
DISPLAY INVISIBLE (-3395 2157);
FORCEPROP 1 LAST PATH I71
J 0
(-3305 2202);
DISPLAY 0.340426 (-3305 2202);
PAINT GREEN (-3305 2202);
DISPLAY INVISIBLE (-3305 2202);
FORCEPROP 1 LAST SIZE 1B
J 0
(-3305 2222);
DISPLAY 0.340426 (-3305 2222);
PAINT GREEN (-3305 2222);
DISPLAY INVISIBLE (-3305 2222);
FORCEADD P3V3_STBY..1
(-6250 4450);
FORCEPROP 3 LASTPIN (-6250 4400) SIG_NAME P3V3_STBY\g
J 0
(-6240 4410);
DISPLAY 0.659574 (-6240 4410);
PAINT MONO (-6240 4410);
DISPLAY INVISIBLE (-6240 4410);
FORCEPROP 1 LAST HDL_POWER P3V3_STBY
J 0
(-6550 4325);
DISPLAY 0.872340 (-6550 4325);
PAINT ORANGE (-6550 4325);
DISPLAY INVISIBLE (-6550 4325);
FORCEPROP 1 LAST PATH I72
J 0
(-6205 4452);
DISPLAY 0.340426 (-6205 4452);
PAINT GREEN (-6205 4452);
DISPLAY INVISIBLE (-6205 4452);
FORCEPROP 1 LAST BODY_TYPE PLUMBING
J 0
(-6295 4407);
DISPLAY 0.340426 (-6295 4407);
PAINT GREEN (-6295 4407);
DISPLAY INVISIBLE (-6295 4407);
FORCEPROP 1 LAST SIZE 1B
J 0
(-6205 4472);
DISPLAY 0.340426 (-6205 4472);
PAINT GREEN (-6205 4472);
DISPLAY INVISIBLE (-6205 4472);
FORCEPROP 2 LAST CDS_LIB mstr_symbols
J 0
(-6250 4450);
PAINT MONO (-6250 4450);
DISPLAY INVISIBLE (-6250 4450);
FORCEPROP 1 LAST VOLTAGE 3.3V
J 0
(-6295 4407);
DISPLAY 0.340426 (-6295 4407);
PAINT SKYBLUE (-6295 4407);
DISPLAY INVISIBLE (-6295 4407);
FORCEADD P3V3_STBY..1
(-1425 2400);
FORCEPROP 3 LASTPIN (-1425 2350) SIG_NAME P3V3_STBY\g
J 0
(-1415 2360);
DISPLAY 0.659574 (-1415 2360);
PAINT MONO (-1415 2360);
DISPLAY INVISIBLE (-1415 2360);
FORCEPROP 1 LAST HDL_POWER P3V3_STBY
J 0
(-1725 2275);
DISPLAY 0.872340 (-1725 2275);
PAINT ORANGE (-1725 2275);
DISPLAY INVISIBLE (-1725 2275);
FORCEPROP 1 LAST PATH I73
J 0
(-1380 2402);
DISPLAY 0.340426 (-1380 2402);
PAINT GREEN (-1380 2402);
DISPLAY INVISIBLE (-1380 2402);
FORCEPROP 1 LAST VOLTAGE 3.3V
J 0
(-1470 2357);
DISPLAY 0.340426 (-1470 2357);
PAINT SKYBLUE (-1470 2357);
DISPLAY INVISIBLE (-1470 2357);
FORCEPROP 2 LAST CDS_LIB mstr_symbols
J 0
(-1425 2400);
PAINT ORANGE (-1425 2400);
DISPLAY INVISIBLE (-1425 2400);
FORCEPROP 1 LAST SIZE 1B
J 0
(-1380 2422);
DISPLAY 0.340426 (-1380 2422);
PAINT GREEN (-1380 2422);
DISPLAY INVISIBLE (-1380 2422);
FORCEPROP 1 LAST BODY_TYPE PLUMBING
J 0
(-1470 2357);
DISPLAY 0.340426 (-1470 2357);
PAINT GREEN (-1470 2357);
DISPLAY INVISIBLE (-1470 2357);
FORCEADD RES..1
(-2650 4450);
FORCEPROP 1 LAST WATTAGE 1/16W
J 2
(-2675 4300);
DISPLAY 0.617021 (-2675 4300);
PAINT SKYBLUE (-2675 4300);
FORCEPROP 1 LAST VALUE 20.0
J 2
(-2675 4350);
DISPLAY 0.617021 (-2675 4350);
PAINT SKYBLUE (-2675 4350);
FORCEPROP 1 LAST TOLERANCE 1%
J 0
(-2650 4350);
DISPLAY 0.617021 (-2650 4350);
PAINT SKYBLUE (-2650 4350);
FORCEPROP 1 LAST LOCATION R1M8
J 0
(-2700 4500);
DISPLAY 0.617021 (-2700 4500);
PAINT AQUA (-2700 4500);
FORCEPROP 1 LASTPIN (-2750 4450) $PN 1
J 0
(-2738 4462);
DISPLAY 0.617021 (-2738 4462);
PAINT ORANGE (-2738 4462);
FORCEPROP 1 LASTPIN (-2550 4450) $PN 2
J 0
(-2588 4462);
DISPLAY 0.617021 (-2588 4462);
PAINT ORANGE (-2588 4462);
FORCEPROP 1 LAST MATERIAL CHIP
J 0
(-2650 4300);
DISPLAY 0.617021 (-2650 4300);
PAINT SKYBLUE (-2650 4300);
FORCEPROP 1 LAST PART_NUMBER G21796-173
J 0
(-2700 4550);
DISPLAY 0.617021 (-2700 4550);
PAINT BLUE (-2700 4550);
FORCEPROP 1 LAST PACK_TYPE 0402
J 0
(-2275 4300);
DISPLAY 0.617021 (-2275 4300);
PAINT SKYBLUE (-2275 4300);
FORCEPROP 2 LAST CDS_LIB mstr_discrete
J 0
(-2650 4450);
PAINT ORANGE (-2650 4450);
DISPLAY INVISIBLE (-2650 4450);
FORCEPROP 2 LAST CDS_LOCATION R1M8
J 0
(-2700 4500);
DISPLAY 0.617021 (-2700 4500);
PAINT AQUA (-2700 4500);
DISPLAY INVISIBLE (-2700 4500);
FORCEPROP 2 LAST ROOM TEMP_SENSORS
J 0
(-2700 4600);
DISPLAY 1.021277 (-2700 4600);
PAINT ORANGE (-2700 4600);
DISPLAY INVISIBLE (-2700 4600);
FORCEPROP 1 LAST PATH I74
J 0
(-2700 4600);
DISPLAY 0.978723 (-2700 4600);
PAINT WHITE (-2700 4600);
DISPLAY INVISIBLE (-2700 4600);
FORCEPROP 0 LAST SEC 1
J 0
(-2700 4600);
DISPLAY 0.680851 (-2700 4600);
PAINT MONO (-2700 4600);
DISPLAY INVISIBLE (-2700 4600);
FORCEPROP 2 LAST SEC_TYPE 0402
J 0
(-2700 4650);
DISPLAY 1.021277 (-2700 4650);
PAINT ORANGE (-2700 4650);
DISPLAY INVISIBLE (-2700 4650);
FORCEPROP 2 LAST BOM_COST SM_THERM
J 0
(-2700 4650);
DISPLAY 1.021277 (-2700 4650);
PAINT ORANGE (-2700 4650);
DISPLAY INVISIBLE (-2700 4650);
FORCEADD RES..1
(-2300 3000);
FORCEPROP 1 LASTPIN (-2400 3000) $PN 1
J 0
(-2388 3012);
DISPLAY 0.617021 (-2388 3012);
PAINT ORANGE (-2388 3012);
FORCEPROP 1 LAST WATTAGE 1/16W
J 2
(-2325 2850);
DISPLAY 0.617021 (-2325 2850);
PAINT SKYBLUE (-2325 2850);
FORCEPROP 1 LAST VALUE 20.0
J 2
(-2325 2900);
DISPLAY 0.617021 (-2325 2900);
PAINT SKYBLUE (-2325 2900);
FORCEPROP 1 LASTPIN (-2200 3000) $PN 2
J 0
(-2238 3012);
DISPLAY 0.617021 (-2238 3012);
PAINT ORANGE (-2238 3012);
FORCEPROP 1 LAST MATERIAL CHIP
J 0
(-2300 2850);
DISPLAY 0.617021 (-2300 2850);
PAINT SKYBLUE (-2300 2850);
FORCEPROP 1 LAST TOLERANCE 1%
J 0
(-2300 2900);
DISPLAY 0.617021 (-2300 2900);
PAINT SKYBLUE (-2300 2900);
FORCEPROP 1 LAST LOCATION R9R7
J 0
(-2350 3050);
DISPLAY 0.617021 (-2350 3050);
PAINT AQUA (-2350 3050);
FORCEPROP 1 LAST PART_NUMBER G21796-173
J 0
(-2350 3100);
DISPLAY 0.617021 (-2350 3100);
PAINT BLUE (-2350 3100);
FORCEPROP 1 LAST PACK_TYPE 0402
J 0
(-1925 2850);
DISPLAY 0.617021 (-1925 2850);
PAINT SKYBLUE (-1925 2850);
FORCEPROP 2 LAST CDS_LIB mstr_discrete
J 0
(-2300 3000);
PAINT ORANGE (-2300 3000);
DISPLAY INVISIBLE (-2300 3000);
FORCEPROP 2 LAST CDS_LOCATION R9R7
J 0
(-2350 3050);
DISPLAY 0.617021 (-2350 3050);
PAINT AQUA (-2350 3050);
DISPLAY INVISIBLE (-2350 3050);
FORCEPROP 2 LAST ROOM TEMP_SENSORS
J 0
(-2350 3150);
DISPLAY 1.021277 (-2350 3150);
PAINT ORANGE (-2350 3150);
DISPLAY INVISIBLE (-2350 3150);
FORCEPROP 1 LAST PATH I75
J 0
(-2350 3150);
DISPLAY 0.978723 (-2350 3150);
PAINT WHITE (-2350 3150);
DISPLAY INVISIBLE (-2350 3150);
FORCEPROP 0 LAST SEC 1
J 0
(-2350 3150);
DISPLAY 0.680851 (-2350 3150);
PAINT MONO (-2350 3150);
DISPLAY INVISIBLE (-2350 3150);
FORCEPROP 2 LAST BOM_COST SM_THERM
J 0
(-2350 3200);
DISPLAY 1.021277 (-2350 3200);
PAINT ORANGE (-2350 3200);
DISPLAY INVISIBLE (-2350 3200);
FORCEPROP 2 LAST SEC_TYPE 0402
J 0
(-2350 3200);
DISPLAY 1.021277 (-2350 3200);
PAINT ORANGE (-2350 3200);
DISPLAY INVISIBLE (-2350 3200);
FORCEADD RES..1
(-2625 3050);
FORCEPROP 1 LAST VALUE 20.0
J 2
(-2650 2950);
DISPLAY 0.617021 (-2650 2950);
PAINT SKYBLUE (-2650 2950);
FORCEPROP 1 LAST TOLERANCE 1%
J 0
(-2625 2950);
DISPLAY 0.617021 (-2625 2950);
PAINT SKYBLUE (-2625 2950);
FORCEPROP 1 LAST WATTAGE 1/16W
J 2
(-2650 2900);
DISPLAY 0.617021 (-2650 2900);
PAINT SKYBLUE (-2650 2900);
FORCEPROP 1 LAST MATERIAL CHIP
J 0
(-2625 2900);
DISPLAY 0.617021 (-2625 2900);
PAINT SKYBLUE (-2625 2900);
FORCEPROP 1 LAST PACK_TYPE 0402
J 0
(-2250 2900);
DISPLAY 0.617021 (-2250 2900);
PAINT SKYBLUE (-2250 2900);
FORCEPROP 1 LASTPIN (-2725 3050) $PN 1
J 0
(-2713 3062);
DISPLAY 0.617021 (-2713 3062);
PAINT ORANGE (-2713 3062);
FORCEPROP 1 LASTPIN (-2525 3050) $PN 2
J 0
(-2563 3062);
DISPLAY 0.617021 (-2563 3062);
PAINT ORANGE (-2563 3062);
FORCEPROP 1 LAST PART_NUMBER G21796-173
J 0
(-2675 3150);
DISPLAY 0.617021 (-2675 3150);
PAINT BLUE (-2675 3150);
FORCEPROP 1 LAST LOCATION R9R8
J 0
(-2675 3100);
DISPLAY 0.617021 (-2675 3100);
PAINT AQUA (-2675 3100);
FORCEPROP 2 LAST CDS_LIB mstr_discrete
J 0
(-2625 3050);
PAINT ORANGE (-2625 3050);
DISPLAY INVISIBLE (-2625 3050);
FORCEPROP 2 LAST ROOM TEMP_SENSORS
J 0
(-2675 3200);
DISPLAY 1.021277 (-2675 3200);
PAINT ORANGE (-2675 3200);
DISPLAY INVISIBLE (-2675 3200);
FORCEPROP 1 LAST PATH I76
J 0
(-2675 3200);
DISPLAY 0.978723 (-2675 3200);
PAINT WHITE (-2675 3200);
DISPLAY INVISIBLE (-2675 3200);
FORCEPROP 2 LAST CDS_LOCATION R9R8
J 0
(-2675 3100);
DISPLAY 0.617021 (-2675 3100);
PAINT AQUA (-2675 3100);
DISPLAY INVISIBLE (-2675 3100);
FORCEPROP 0 LAST SEC 1
J 0
(-2675 3200);
DISPLAY 0.680851 (-2675 3200);
PAINT MONO (-2675 3200);
DISPLAY INVISIBLE (-2675 3200);
FORCEPROP 2 LAST BOM_COST SM_THERM
J 0
(-2675 3250);
DISPLAY 1.021277 (-2675 3250);
PAINT ORANGE (-2675 3250);
DISPLAY INVISIBLE (-2675 3250);
FORCEPROP 2 LAST SEC_TYPE 0402
J 0
(-2675 3250);
DISPLAY 1.021277 (-2675 3250);
PAINT ORANGE (-2675 3250);
DISPLAY INVISIBLE (-2675 3250);
FORCEADD RES..1
(-6725 1325);
FORCEPROP 1 LAST VALUE 20.0
J 2
(-6775 1275);
DISPLAY 0.617021 (-6775 1275);
PAINT SKYBLUE (-6775 1275);
FORCEPROP 1 LASTPIN (-6825 1325) $PN 1
J 0
(-6813 1337);
DISPLAY 0.617021 (-6813 1337);
PAINT ORANGE (-6813 1337);
FORCEPROP 1 LASTPIN (-6625 1325) $PN 2
J 0
(-6663 1337);
DISPLAY 0.617021 (-6663 1337);
PAINT ORANGE (-6663 1337);
FORCEPROP 1 LAST LOCATION R9G14
J 0
(-6750 1375);
DISPLAY 0.617021 (-6750 1375);
PAINT AQUA (-6750 1375);
FORCEPROP 1 LAST TOLERANCE 1%
J 0
(-6650 1275);
DISPLAY 0.617021 (-6650 1275);
PAINT SKYBLUE (-6650 1275);
FORCEPROP 1 LAST MATERIAL CHIP
J 0
(-6575 1275);
DISPLAY 0.617021 (-6575 1275);
PAINT SKYBLUE (-6575 1275);
FORCEPROP 1 LAST PART_NUMBER G21796-173
J 0
(-6475 1275);
DISPLAY 0.617021 (-6475 1275);
PAINT BLUE (-6475 1275);
FORCEPROP 1 LAST WATTAGE 1/16W
J 2
(-6850 1275);
DISPLAY 0.617021 (-6850 1275);
PAINT SKYBLUE (-6850 1275);
DISPLAY INVISIBLE (-6850 1275);
FORCEPROP 2 LAST CDS_LOCATION R9G14
J 0
(-6750 1375);
DISPLAY 0.617021 (-6750 1375);
PAINT AQUA (-6750 1375);
DISPLAY INVISIBLE (-6750 1375);
FORCEPROP 2 LAST CDS_LIB mstr_discrete
J 0
(-6725 1325);
PAINT MONO (-6725 1325);
DISPLAY INVISIBLE (-6725 1325);
FORCEPROP 1 LAST PATH I77
J 0
(-6775 1475);
DISPLAY 0.978723 (-6775 1475);
PAINT WHITE (-6775 1475);
DISPLAY INVISIBLE (-6775 1475);
FORCEPROP 2 LAST $SEC 1
J 0
(-6775 1525);
PAINT MONO (-6775 1525);
DISPLAY INVISIBLE (-6775 1525);
FORCEPROP 2 LAST CDS_SEC 1
J 0
(-6775 1525);
PAINT MONO (-6775 1525);
DISPLAY INVISIBLE (-6775 1525);
FORCEPROP 1 LAST PACK_TYPE 0402
J 0
(-6575 1275);
DISPLAY 0.617021 (-6575 1275);
PAINT SKYBLUE (-6575 1275);
DISPLAY INVISIBLE (-6575 1275);
FORCEPROP 0 LAST ROOM SMBUS
J 0
(-6475 1375);
DISPLAY 1.021277 (-6475 1375);
PAINT ORANGE (-6475 1375);
DISPLAY INVISIBLE (-6475 1375);
FORCEPROP 0 LAST BOM_COST SM_CONTROLLER
J 0
(-6475 1475);
DISPLAY 1.021277 (-6475 1475);
PAINT ORANGE (-6475 1475);
DISPLAY INVISIBLE (-6475 1475);
FORCEPROP 0 LAST SKU B
J 0
(-6475 1375);
DISPLAY 1.021277 (-6475 1375);
PAINT ORANGE (-6475 1375);
DISPLAY INVISIBLE (-6475 1375);
FORCEADD RES..1
(-6725 1150);
FORCEPROP 1 LASTPIN (-6825 1150) $PN 1
J 0
(-6813 1162);
DISPLAY 0.617021 (-6813 1162);
PAINT ORANGE (-6813 1162);
FORCEPROP 1 LAST VALUE 20.0
J 2
(-6775 1100);
DISPLAY 0.617021 (-6775 1100);
PAINT SKYBLUE (-6775 1100);
FORCEPROP 1 LASTPIN (-6625 1150) $PN 2
J 0
(-6663 1162);
DISPLAY 0.617021 (-6663 1162);
PAINT ORANGE (-6663 1162);
FORCEPROP 1 LAST LOCATION R1U31
J 0
(-6750 1200);
DISPLAY 0.617021 (-6750 1200);
PAINT AQUA (-6750 1200);
FORCEPROP 1 LAST MATERIAL CHIP
J 0
(-6575 1100);
DISPLAY 0.617021 (-6575 1100);
PAINT SKYBLUE (-6575 1100);
FORCEPROP 1 LAST TOLERANCE 1%
J 0
(-6650 1100);
DISPLAY 0.617021 (-6650 1100);
PAINT SKYBLUE (-6650 1100);
FORCEPROP 1 LAST PART_NUMBER G21796-173
J 0
(-6475 1100);
DISPLAY 0.617021 (-6475 1100);
PAINT BLUE (-6475 1100);
FORCEPROP 1 LAST WATTAGE 1/16W
J 2
(-6850 1100);
DISPLAY 0.617021 (-6850 1100);
PAINT SKYBLUE (-6850 1100);
DISPLAY INVISIBLE (-6850 1100);
FORCEPROP 2 LAST CDS_LIB mstr_discrete
J 0
(-6725 1150);
PAINT MONO (-6725 1150);
DISPLAY INVISIBLE (-6725 1150);
FORCEPROP 2 LAST CDS_LOCATION R1U31
J 0
(-6750 1200);
DISPLAY 0.617021 (-6750 1200);
PAINT AQUA (-6750 1200);
DISPLAY INVISIBLE (-6750 1200);
FORCEPROP 1 LAST PATH I78
J 0
(-6775 1300);
DISPLAY 0.978723 (-6775 1300);
PAINT WHITE (-6775 1300);
DISPLAY INVISIBLE (-6775 1300);
FORCEPROP 2 LAST $SEC 1
J 0
(-6775 1350);
PAINT MONO (-6775 1350);
DISPLAY INVISIBLE (-6775 1350);
FORCEPROP 2 LAST CDS_SEC 1
J 0
(-6775 1350);
PAINT MONO (-6775 1350);
DISPLAY INVISIBLE (-6775 1350);
FORCEPROP 0 LAST ROOM SMBUS
J 0
(-6475 1200);
DISPLAY 1.021277 (-6475 1200);
PAINT ORANGE (-6475 1200);
DISPLAY INVISIBLE (-6475 1200);
FORCEPROP 0 LAST SKU B
J 0
(-6475 1200);
DISPLAY 1.021277 (-6475 1200);
PAINT ORANGE (-6475 1200);
DISPLAY INVISIBLE (-6475 1200);
FORCEPROP 1 LAST PACK_TYPE 0402
J 0
(-6575 1100);
DISPLAY 0.617021 (-6575 1100);
PAINT SKYBLUE (-6575 1100);
DISPLAY INVISIBLE (-6575 1100);
FORCEPROP 0 LAST BOM_COST SM_CONTROLLER
J 0
(-6475 1300);
DISPLAY 1.021277 (-6475 1300);
PAINT ORANGE (-6475 1300);
DISPLAY INVISIBLE (-6475 1300);
FORCEADD RES..1
(-6725 1025);
FORCEPROP 1 LAST MATERIAL CHIP
J 0
(-6575 975);
DISPLAY 0.617021 (-6575 975);
PAINT SKYBLUE (-6575 975);
FORCEPROP 1 LAST TOLERANCE 1%
J 0
(-6650 975);
DISPLAY 0.617021 (-6650 975);
PAINT SKYBLUE (-6650 975);
FORCEPROP 1 LAST VALUE 20.0
J 2
(-6775 975);
DISPLAY 0.617021 (-6775 975);
PAINT SKYBLUE (-6775 975);
FORCEPROP 1 LAST PART_NUMBER G21796-173
J 0
(-6475 975);
DISPLAY 0.617021 (-6475 975);
PAINT BLUE (-6475 975);
FORCEPROP 1 LASTPIN (-6825 1025) $PN 1
J 0
(-6813 1037);
DISPLAY 0.617021 (-6813 1037);
PAINT ORANGE (-6813 1037);
FORCEPROP 1 LASTPIN (-6625 1025) $PN 2
J 0
(-6663 1037);
DISPLAY 0.617021 (-6663 1037);
PAINT ORANGE (-6663 1037);
FORCEPROP 1 LAST LOCATION R1U25
J 0
(-6775 1075);
DISPLAY 0.617021 (-6775 1075);
PAINT AQUA (-6775 1075);
FORCEPROP 1 LAST WATTAGE 1/16W
J 2
(-6850 975);
DISPLAY 0.617021 (-6850 975);
PAINT SKYBLUE (-6850 975);
DISPLAY INVISIBLE (-6850 975);
FORCEPROP 1 LAST PACK_TYPE 0402
J 0
(-6575 975);
DISPLAY 0.617021 (-6575 975);
PAINT SKYBLUE (-6575 975);
DISPLAY INVISIBLE (-6575 975);
FORCEPROP 2 LAST CDS_LOCATION R1U25
J 0
(-6775 1075);
DISPLAY 0.617021 (-6775 1075);
PAINT AQUA (-6775 1075);
DISPLAY INVISIBLE (-6775 1075);
FORCEPROP 2 LAST CDS_LIB mstr_discrete
J 0
(-6725 1025);
PAINT MONO (-6725 1025);
DISPLAY INVISIBLE (-6725 1025);
FORCEPROP 1 LAST PATH I79
J 0
(-6775 1175);
DISPLAY 0.978723 (-6775 1175);
PAINT WHITE (-6775 1175);
DISPLAY INVISIBLE (-6775 1175);
FORCEPROP 2 LAST $SEC 1
J 0
(-6775 1225);
PAINT MONO (-6775 1225);
DISPLAY INVISIBLE (-6775 1225);
FORCEPROP 2 LAST CDS_SEC 1
J 0
(-6775 1225);
PAINT MONO (-6775 1225);
DISPLAY INVISIBLE (-6775 1225);
FORCEPROP 0 LAST ROOM SMBUS
J 0
(-6475 1075);
DISPLAY 1.021277 (-6475 1075);
PAINT ORANGE (-6475 1075);
DISPLAY INVISIBLE (-6475 1075);
FORCEPROP 0 LAST BOM_COST SM_CONTROLLER
J 0
(-6475 1175);
DISPLAY 1.021277 (-6475 1175);
PAINT ORANGE (-6475 1175);
DISPLAY INVISIBLE (-6475 1175);
FORCEPROP 0 LAST SKU B
J 0
(-6475 1075);
DISPLAY 1.021277 (-6475 1075);
PAINT ORANGE (-6475 1075);
DISPLAY INVISIBLE (-6475 1075);
FORCEADD RES..1
(-2950 4500);
FORCEPROP 1 LAST WATTAGE 1/16W
J 2
(-2975 4350);
DISPLAY 0.617021 (-2975 4350);
PAINT SKYBLUE (-2975 4350);
FORCEPROP 1 LAST VALUE 20.0
J 2
(-2975 4400);
DISPLAY 0.617021 (-2975 4400);
PAINT SKYBLUE (-2975 4400);
FORCEPROP 1 LAST MATERIAL CHIP
J 0
(-2950 4350);
DISPLAY 0.617021 (-2950 4350);
PAINT SKYBLUE (-2950 4350);
FORCEPROP 1 LASTPIN (-3050 4500) $PN 1
J 0
(-3038 4512);
DISPLAY 0.617021 (-3038 4512);
PAINT ORANGE (-3038 4512);
FORCEPROP 1 LAST TOLERANCE 1%
J 0
(-2950 4400);
DISPLAY 0.617021 (-2950 4400);
PAINT SKYBLUE (-2950 4400);
FORCEPROP 1 LAST LOCATION R1M9
J 0
(-3000 4550);
DISPLAY 0.617021 (-3000 4550);
PAINT AQUA (-3000 4550);
FORCEPROP 1 LASTPIN (-2850 4500) $PN 2
J 0
(-2888 4512);
DISPLAY 0.617021 (-2888 4512);
PAINT ORANGE (-2888 4512);
FORCEPROP 1 LAST PART_NUMBER G21796-173
J 0
(-3000 4600);
DISPLAY 0.617021 (-3000 4600);
PAINT BLUE (-3000 4600);
FORCEPROP 1 LAST PACK_TYPE 0402
J 0
(-2575 4350);
DISPLAY 0.617021 (-2575 4350);
PAINT SKYBLUE (-2575 4350);
FORCEPROP 2 LAST CDS_LOCATION R1M9
J 0
(-3000 4550);
DISPLAY 0.617021 (-3000 4550);
PAINT AQUA (-3000 4550);
DISPLAY INVISIBLE (-3000 4550);
FORCEPROP 2 LAST CDS_LIB mstr_discrete
J 0
(-2950 4500);
PAINT ORANGE (-2950 4500);
DISPLAY INVISIBLE (-2950 4500);
FORCEPROP 2 LAST ROOM TEMP_SENSORS
J 0
(-3000 4650);
DISPLAY 1.021277 (-3000 4650);
PAINT ORANGE (-3000 4650);
DISPLAY INVISIBLE (-3000 4650);
FORCEPROP 1 LAST PATH I8
J 0
(-3000 4650);
DISPLAY 0.978723 (-3000 4650);
PAINT WHITE (-3000 4650);
DISPLAY INVISIBLE (-3000 4650);
FORCEPROP 0 LAST SEC 1
J 0
(-3000 4650);
DISPLAY 0.680851 (-3000 4650);
PAINT MONO (-3000 4650);
DISPLAY INVISIBLE (-3000 4650);
FORCEPROP 2 LAST SEC_TYPE 0402
J 0
(-3000 4700);
DISPLAY 1.021277 (-3000 4700);
PAINT ORANGE (-3000 4700);
DISPLAY INVISIBLE (-3000 4700);
FORCEPROP 2 LAST BOM_COST SM_THERM
J 0
(-3000 4700);
DISPLAY 1.021277 (-3000 4700);
PAINT ORANGE (-3000 4700);
DISPLAY INVISIBLE (-3000 4700);
FORCEADD RES..2
(-6075 1950);
FORCEPROP 1 LAST PACK_TYPE 0402
J 0
(-6035 1775);
DISPLAY 0.617021 (-6035 1775);
PAINT SKYBLUE (-6035 1775);
FORCEPROP 1 LASTPIN (-6075 1850) $PN 2
J 0
(-6070 1860);
DISPLAY 0.617021 (-6070 1860);
PAINT ORANGE (-6070 1860);
FORCEPROP 1 LASTPIN (-6075 2050) $PN 1
J 0
(-6070 2012);
DISPLAY 0.617021 (-6070 2012);
PAINT ORANGE (-6070 2012);
FORCEPROP 1 LAST TOLERANCE 1.0%
J 0
(-6030 1975);
DISPLAY 0.617021 (-6030 1975);
PAINT SKYBLUE (-6030 1975);
FORCEPROP 1 LAST MATERIAL CHIP
J 0
(-6035 1875);
DISPLAY 0.617021 (-6035 1875);
PAINT SKYBLUE (-6035 1875);
FORCEPROP 1 LAST WATTAGE 1/16W
J 0
(-6035 1925);
DISPLAY 0.617021 (-6035 1925);
PAINT SKYBLUE (-6035 1925);
FORCEPROP 1 LAST PART_NUMBER G21796-235
J 0
(-6035 1825);
DISPLAY 0.617021 (-6035 1825);
PAINT BLUE (-6035 1825);
FORCEPROP 1 LAST VALUE 665
J 0
(-6030 2025);
DISPLAY 0.617021 (-6030 2025);
PAINT SKYBLUE (-6030 2025);
FORCEPROP 1 LAST LOCATION R2U38
J 0
(-6030 2075);
DISPLAY 0.617021 (-6030 2075);
PAINT AQUA (-6030 2075);
FORCEPROP 2 LAST CDS_LIB mstr_discrete
J 0
(-6075 1950);
PAINT ORANGE (-6075 1950);
DISPLAY INVISIBLE (-6075 1950);
FORCEPROP 2 LAST CDS_LOCATION R2U38
J 0
(-6030 2075);
DISPLAY 0.617021 (-6030 2075);
PAINT AQUA (-6030 2075);
DISPLAY INVISIBLE (-6030 2075);
FORCEPROP 0 LAST SEC 1
J 0
(-6025 2125);
DISPLAY 0.680851 (-6025 2125);
PAINT MONO (-6025 2125);
DISPLAY INVISIBLE (-6025 2125);
FORCEPROP 1 LAST PATH I80
J 0
(-6025 2125);
DISPLAY 0.978723 (-6025 2125);
PAINT WHITE (-6025 2125);
DISPLAY INVISIBLE (-6025 2125);
FORCEPROP 2 LAST SEC_TYPE 0402
J 0
(-6025 2175);
DISPLAY 1.021277 (-6025 2175);
PAINT ORANGE (-6025 2175);
DISPLAY INVISIBLE (-6025 2175);
FORCEPROP 0 LAST ROOM SMBUS
J 0
(-6025 2175);
DISPLAY 1.021277 (-6025 2175);
PAINT ORANGE (-6025 2175);
DISPLAY INVISIBLE (-6025 2175);
FORCEPROP 0 LAST BOM_COST SM_CONTROLLER
J 0
(-6025 2275);
DISPLAY 1.021277 (-6025 2275);
PAINT ORANGE (-6025 2275);
DISPLAY INVISIBLE (-6025 2275);
FORCEADD P3V3_STBY..1
(-6075 2200);
FORCEPROP 3 LASTPIN (-6075 2150) SIG_NAME P3V3_STBY\g
J 0
(-6065 2160);
DISPLAY 0.659574 (-6065 2160);
PAINT MONO (-6065 2160);
DISPLAY INVISIBLE (-6065 2160);
FORCEPROP 1 LAST HDL_POWER P3V3_STBY
J 0
(-6375 2075);
DISPLAY 0.872340 (-6375 2075);
PAINT ORANGE (-6375 2075);
DISPLAY INVISIBLE (-6375 2075);
FORCEPROP 1 LAST BODY_TYPE PLUMBING
J 0
(-6120 2157);
DISPLAY 0.340426 (-6120 2157);
PAINT GREEN (-6120 2157);
DISPLAY INVISIBLE (-6120 2157);
FORCEPROP 1 LAST VOLTAGE 3.3V
J 0
(-6120 2157);
DISPLAY 0.340426 (-6120 2157);
PAINT SKYBLUE (-6120 2157);
DISPLAY INVISIBLE (-6120 2157);
FORCEPROP 2 LAST CDS_LIB mstr_symbols
J 0
(-6075 2200);
PAINT ORANGE (-6075 2200);
DISPLAY INVISIBLE (-6075 2200);
FORCEPROP 1 LAST SIZE 1B
J 0
(-6030 2222);
DISPLAY 0.340426 (-6030 2222);
PAINT GREEN (-6030 2222);
DISPLAY INVISIBLE (-6030 2222);
FORCEPROP 1 LAST PATH I81
J 0
(-6030 2202);
DISPLAY 0.340426 (-6030 2202);
PAINT GREEN (-6030 2202);
DISPLAY INVISIBLE (-6030 2202);
FORCEADD P3V3_STBY..1
(-6425 2200);
FORCEPROP 3 LASTPIN (-6425 2150) SIG_NAME P3V3_STBY\g
J 0
(-6415 2160);
DISPLAY 0.659574 (-6415 2160);
PAINT MONO (-6415 2160);
DISPLAY INVISIBLE (-6415 2160);
FORCEPROP 1 LAST HDL_POWER P3V3_STBY
J 0
(-6725 2075);
DISPLAY 0.872340 (-6725 2075);
PAINT ORANGE (-6725 2075);
DISPLAY INVISIBLE (-6725 2075);
FORCEPROP 1 LAST VOLTAGE 3.3V
J 0
(-6470 2157);
DISPLAY 0.340426 (-6470 2157);
PAINT SKYBLUE (-6470 2157);
DISPLAY INVISIBLE (-6470 2157);
FORCEPROP 2 LAST CDS_LIB mstr_symbols
J 0
(-6425 2200);
PAINT ORANGE (-6425 2200);
DISPLAY INVISIBLE (-6425 2200);
FORCEPROP 1 LAST BODY_TYPE PLUMBING
J 0
(-6470 2157);
DISPLAY 0.340426 (-6470 2157);
PAINT GREEN (-6470 2157);
DISPLAY INVISIBLE (-6470 2157);
FORCEPROP 1 LAST SIZE 1B
J 0
(-6380 2222);
DISPLAY 0.340426 (-6380 2222);
PAINT GREEN (-6380 2222);
DISPLAY INVISIBLE (-6380 2222);
FORCEPROP 1 LAST PATH I82
J 0
(-6380 2202);
DISPLAY 0.340426 (-6380 2202);
PAINT GREEN (-6380 2202);
DISPLAY INVISIBLE (-6380 2202);
FORCEADD RES..2
(-6425 1950);
FORCEPROP 1 LASTPIN (-6425 1850) $PN 2
J 0
(-6420 1860);
DISPLAY 0.617021 (-6420 1860);
PAINT ORANGE (-6420 1860);
FORCEPROP 1 LASTPIN (-6425 2050) $PN 1
J 0
(-6420 2012);
DISPLAY 0.617021 (-6420 2012);
PAINT ORANGE (-6420 2012);
FORCEPROP 1 LAST TOLERANCE 1.0%
J 0
(-6380 1975);
DISPLAY 0.617021 (-6380 1975);
PAINT SKYBLUE (-6380 1975);
FORCEPROP 1 LAST PACK_TYPE 0402
J 0
(-6385 1775);
DISPLAY 0.617021 (-6385 1775);
PAINT SKYBLUE (-6385 1775);
FORCEPROP 1 LAST MATERIAL CHIP
J 0
(-6385 1875);
DISPLAY 0.617021 (-6385 1875);
PAINT SKYBLUE (-6385 1875);
FORCEPROP 1 LAST WATTAGE 1/16W
J 0
(-6385 1925);
DISPLAY 0.617021 (-6385 1925);
PAINT SKYBLUE (-6385 1925);
FORCEPROP 1 LAST VALUE 665
J 0
(-6380 2025);
DISPLAY 0.617021 (-6380 2025);
PAINT SKYBLUE (-6380 2025);
FORCEPROP 1 LAST LOCATION R2U39
J 0
(-6380 2075);
DISPLAY 0.617021 (-6380 2075);
PAINT AQUA (-6380 2075);
FORCEPROP 1 LAST PART_NUMBER G21796-235
J 0
(-6385 1825);
DISPLAY 0.617021 (-6385 1825);
PAINT BLUE (-6385 1825);
FORCEPROP 2 LAST CDS_LIB mstr_discrete
J 0
(-6425 1950);
PAINT ORANGE (-6425 1950);
DISPLAY INVISIBLE (-6425 1950);
FORCEPROP 0 LAST BOM_COST SM_CONTROLLER
J 0
(-6375 2275);
DISPLAY 1.021277 (-6375 2275);
PAINT ORANGE (-6375 2275);
DISPLAY INVISIBLE (-6375 2275);
FORCEPROP 2 LAST SEC_TYPE 0402
J 0
(-6375 2175);
DISPLAY 1.021277 (-6375 2175);
PAINT ORANGE (-6375 2175);
DISPLAY INVISIBLE (-6375 2175);
FORCEPROP 0 LAST SEC 1
J 0
(-6375 2125);
DISPLAY 0.680851 (-6375 2125);
PAINT MONO (-6375 2125);
DISPLAY INVISIBLE (-6375 2125);
FORCEPROP 2 LAST CDS_LOCATION R2U39
J 0
(-6380 2075);
DISPLAY 0.617021 (-6380 2075);
PAINT AQUA (-6380 2075);
DISPLAY INVISIBLE (-6380 2075);
FORCEPROP 1 LAST PATH I83
J 0
(-6375 2125);
DISPLAY 0.978723 (-6375 2125);
PAINT WHITE (-6375 2125);
DISPLAY INVISIBLE (-6375 2125);
FORCEPROP 0 LAST ROOM SMBUS
J 0
(-6375 2175);
DISPLAY 1.021277 (-6375 2175);
PAINT ORANGE (-6375 2175);
DISPLAY INVISIBLE (-6375 2175);
FORCEADD RES..1
(-3975 1550);
FORCEPROP 1 LAST WATTAGE 1/16W
J 2
(-4000 1400);
DISPLAY 0.617021 (-4000 1400);
PAINT SKYBLUE (-4000 1400);
FORCEPROP 1 LAST VALUE 20.0
J 2
(-4000 1450);
DISPLAY 0.617021 (-4000 1450);
PAINT SKYBLUE (-4000 1450);
FORCEPROP 1 LAST TOLERANCE 1%
J 0
(-3975 1450);
DISPLAY 0.617021 (-3975 1450);
PAINT SKYBLUE (-3975 1450);
FORCEPROP 1 LAST PACK_TYPE 0402
J 0
(-3725 1400);
DISPLAY 0.617021 (-3725 1400);
PAINT SKYBLUE (-3725 1400);
FORCEPROP 1 LAST MATERIAL CHIP
J 0
(-3975 1400);
DISPLAY 0.617021 (-3975 1400);
PAINT SKYBLUE (-3975 1400);
FORCEPROP 1 LAST LOCATION R8D24
J 0
(-4025 1600);
DISPLAY 0.617021 (-4025 1600);
PAINT AQUA (-4025 1600);
FORCEPROP 1 LASTPIN (-4075 1550) $PN 1
J 0
(-4063 1562);
DISPLAY 0.617021 (-4063 1562);
PAINT ORANGE (-4063 1562);
FORCEPROP 1 LASTPIN (-3875 1550) $PN 2
J 0
(-3913 1562);
DISPLAY 0.617021 (-3913 1562);
PAINT ORANGE (-3913 1562);
FORCEPROP 1 LAST PART_NUMBER G21796-173
J 0
(-4025 1650);
DISPLAY 0.617021 (-4025 1650);
PAINT BLUE (-4025 1650);
FORCEPROP 1 LAST PATH I84
J 0
(-4025 1700);
DISPLAY 0.978723 (-4025 1700);
PAINT WHITE (-4025 1700);
DISPLAY INVISIBLE (-4025 1700);
FORCEPROP 2 LAST CDS_LOCATION R8D24
J 0
(-4025 1600);
DISPLAY 0.617021 (-4025 1600);
PAINT AQUA (-4025 1600);
DISPLAY INVISIBLE (-4025 1600);
FORCEPROP 0 LAST SEC 1
J 0
(-4025 1700);
DISPLAY 0.680851 (-4025 1700);
PAINT MONO (-4025 1700);
DISPLAY INVISIBLE (-4025 1700);
FORCEPROP 2 LAST CDS_LIB mstr_discrete
J 0
(-3975 1550);
PAINT ORANGE (-3975 1550);
DISPLAY INVISIBLE (-3975 1550);
FORCEPROP 0 LAST ROOM TEMP_SENSORS
J 0
(-4025 1750);
DISPLAY 1.021277 (-4025 1750);
PAINT ORANGE (-4025 1750);
DISPLAY INVISIBLE (-4025 1750);
FORCEPROP 2 LAST SEC_TYPE 0402
J 0
(-4025 1750);
DISPLAY 1.021277 (-4025 1750);
PAINT ORANGE (-4025 1750);
DISPLAY INVISIBLE (-4025 1750);
FORCEPROP 0 LAST BOM_COST SM_THERM
J 0
(-4025 1850);
DISPLAY 1.021277 (-4025 1850);
PAINT ORANGE (-4025 1850);
DISPLAY INVISIBLE (-4025 1850);
FORCEADD RES..1
(-1525 1550);
FORCEPROP 1 LAST WATTAGE 1/16W
J 2
(-1550 1400);
DISPLAY 0.617021 (-1550 1400);
PAINT SKYBLUE (-1550 1400);
FORCEPROP 1 LAST VALUE 20.0
J 2
(-1550 1450);
DISPLAY 0.617021 (-1550 1450);
PAINT SKYBLUE (-1550 1450);
FORCEPROP 1 LAST PART_NUMBER G21796-173
J 0
(-1575 1650);
DISPLAY 0.617021 (-1575 1650);
PAINT BLUE (-1575 1650);
FORCEPROP 1 LAST LOCATION R8D23
J 0
(-1575 1600);
DISPLAY 0.617021 (-1575 1600);
PAINT AQUA (-1575 1600);
FORCEPROP 1 LAST MATERIAL CHIP
J 0
(-1525 1400);
DISPLAY 0.617021 (-1525 1400);
PAINT SKYBLUE (-1525 1400);
FORCEPROP 1 LAST TOLERANCE 1%
J 0
(-1525 1450);
DISPLAY 0.617021 (-1525 1450);
PAINT SKYBLUE (-1525 1450);
FORCEPROP 1 LAST PACK_TYPE 0402
J 0
(-1275 1400);
DISPLAY 0.617021 (-1275 1400);
PAINT SKYBLUE (-1275 1400);
FORCEPROP 1 LASTPIN (-1625 1550) $PN 1
J 0
(-1613 1562);
DISPLAY 0.787234 (-1613 1562);
PAINT ORANGE (-1613 1562);
DISPLAY INVISIBLE (-1613 1562);
FORCEPROP 0 LAST ROOM TEMP_SENSORS
J 0
(-1575 1750);
DISPLAY 1.021277 (-1575 1750);
PAINT ORANGE (-1575 1750);
DISPLAY INVISIBLE (-1575 1750);
FORCEPROP 1 LAST PATH I85
J 0
(-1575 1700);
DISPLAY 0.978723 (-1575 1700);
PAINT WHITE (-1575 1700);
DISPLAY INVISIBLE (-1575 1700);
FORCEPROP 2 LAST CDS_LOCATION R8D23
J 0
(-1575 1600);
DISPLAY 0.617021 (-1575 1600);
PAINT AQUA (-1575 1600);
DISPLAY INVISIBLE (-1575 1600);
FORCEPROP 2 LAST $SEC 1
J 0
(-1575 1750);
PAINT MONO (-1575 1750);
DISPLAY INVISIBLE (-1575 1750);
FORCEPROP 2 LAST CDS_SEC 1
J 0
(-1575 1750);
PAINT MONO (-1575 1750);
DISPLAY INVISIBLE (-1575 1750);
FORCEPROP 0 LAST BOM_COST SM_THERM
J 0
(-1575 1850);
DISPLAY 1.021277 (-1575 1850);
PAINT ORANGE (-1575 1850);
DISPLAY INVISIBLE (-1575 1850);
FORCEPROP 2 LAST CDS_LIB mstr_discrete
J 0
(-1525 1550);
PAINT ORANGE (-1525 1550);
DISPLAY INVISIBLE (-1525 1550);
FORCEPROP 1 LASTPIN (-1425 1550) $PN 2
J 0
(-1463 1562);
DISPLAY 0.787234 (-1463 1562);
PAINT ORANGE (-1463 1562);
DISPLAY INVISIBLE (-1463 1562);
FORCEADD OFFPAGE..1
(-4725 1550);
FORCEPROP 2 LAST $XR0 167 
J 0
(-4977 1550);
DISPLAY 0.638298 (-4977 1550);
PAINT MONO (-4977 1550);
FORCEPROP 2 LAST $XR1 184 
J 0
(-5097 1550);
DISPLAY 0.638298 (-5097 1550);
PAINT MONO (-5097 1550);
FORCEPROP 2 LAST $XR2 191 
J 0
(-5217 1550);
DISPLAY 0.638298 (-5217 1550);
PAINT MONO (-5217 1550);
FORCEPROP 2 LAST PATH I86
J 0
(-4675 1625);
DISPLAY 1.021277 (-4675 1625);
PAINT ORANGE (-4675 1625);
DISPLAY INVISIBLE (-4675 1625);
FORCEPROP 2 LAST CDS_LIB mstr_standard
J 0
(-4725 1550);
PAINT ORANGE (-4725 1550);
DISPLAY INVISIBLE (-4725 1550);
FORCEPROP 1 LAST COMMENT_BODY TRUE
J 0
(-4600 1450);
DISPLAY 0.872340 (-4600 1450);
PAINT GREEN (-4600 1450);
DISPLAY INVISIBLE (-4600 1450);
FORCEPROP 1 LAST OFFPAGE TRUE
J 0
(-4400 1425);
DISPLAY 0.872340 (-4400 1425);
PAINT GREEN (-4400 1425);
DISPLAY INVISIBLE (-4400 1425);
FORCEADD OFFPAGE..3
(-675 1550);
FORCEPROP 2 LAST $XR0 167 
J 0
(-461 1550);
DISPLAY 0.638298 (-461 1550);
PAINT MONO (-461 1550);
FORCEPROP 2 LAST $XR1 184 
J 0
(-341 1550);
DISPLAY 0.638298 (-341 1550);
PAINT MONO (-341 1550);
FORCEPROP 2 LAST $XR2 191 
J 0
(-461 1514);
DISPLAY 0.638298 (-461 1514);
PAINT MONO (-461 1514);
FORCEPROP 1 LAST COMMENT_BODY TRUE
J 0
(-725 1450);
DISPLAY 0.872340 (-725 1450);
PAINT GREEN (-725 1450);
DISPLAY INVISIBLE (-725 1450);
FORCEPROP 2 LAST PATH I87
J 0
(-625 1625);
DISPLAY 1.021277 (-625 1625);
PAINT ORANGE (-625 1625);
DISPLAY INVISIBLE (-625 1625);
FORCEPROP 2 LAST CDS_LIB mstr_standard
J 0
(-675 1550);
PAINT ORANGE (-675 1550);
DISPLAY INVISIBLE (-675 1550);
FORCEPROP 1 LAST OFFPAGE TRUE
J 0
(-350 1425);
DISPLAY 0.872340 (-350 1425);
PAINT GREEN (-350 1425);
DISPLAY INVISIBLE (-350 1425);
FORCEADD CAD_NOTE..1
(-3275 3575);
FORCEPROP 0 LAST L1 PLACE LOWER TMP421 ON EDGE OF BOARD NEAR AIRMAX CONNECTORS
J 0
(-3425 3450);
DISPLAY 0.808511 (-3425 3450);
PAINT ORANGE (-3425 3450);
FORCEPROP 2 LAST CDS_LIB mstr_symbols
J 0
(-3275 3575);
PAINT ORANGE (-3275 3575);
DISPLAY INVISIBLE (-3275 3575);
FORCEPROP 1 LAST COMMENT_BODY TRUE
J 0
(-3250 3675);
DISPLAY 0.978723 (-3250 3675);
PAINT ORANGE (-3250 3675);
DISPLAY INVISIBLE (-3250 3675);
FORCEADD DESIGN_NOTE..1
(-2100 1300);
FORCEPROP 1 LAST COMMENT_BODY TRUE
J 0
(-2075 1400);
DISPLAY 0.978723 (-2075 1400);
PAINT ORANGE (-2075 1400);
DISPLAY INVISIBLE (-2075 1400);
FORCEPROP 2 LAST CDS_LIB mstr_symbols
J 0
(-2100 1300);
PAINT ORANGE (-2100 1300);
DISPLAY INVISIBLE (-2100 1300);
FORCEADD CAD_NOTE..1
(-4425 1025);
FORCEPROP 0 LAST L1 PLACE SERIES RESISTORS ON SMB_SENSOR_STBY_LVC3_SDA/SCL NETS CLOSE TO AT24C64
J 0
(-4575 875);
DISPLAY 0.808511 (-4575 875);
PAINT ORANGE (-4575 875);
FORCEPROP 1 LAST COMMENT_BODY TRUE
J 0
(-4400 1125);
DISPLAY 0.978723 (-4400 1125);
PAINT ORANGE (-4400 1125);
DISPLAY INVISIBLE (-4400 1125);
FORCEPROP 2 LAST CDS_LIB mstr_symbols
J 0
(-4425 1025);
PAINT ORANGE (-4425 1025);
DISPLAY INVISIBLE (-4425 1025);
FORCEADD CAD_NOTE..1
(-3275 5125);
FORCEPROP 0 LAST L1 PLACE UPPER TMP421 ON EDGE OF BOARD NEAR RJ 45
J 0
(-3425 5000);
DISPLAY 1.021277 (-3425 5000);
PAINT ORANGE (-3425 5000);
FORCEPROP 1 LAST COMMENT_BODY TRUE
J 0
(-3250 5225);
DISPLAY 0.978723 (-3250 5225);
PAINT ORANGE (-3250 5225);
DISPLAY INVISIBLE (-3250 5225);
FORCEPROP 2 LAST CDS_LIB mstr_symbols
J 0
(-3275 5125);
PAINT ORANGE (-3275 5125);
DISPLAY INVISIBLE (-3275 5125);
FORCEADD DESIGN_NOTE..1
(-6575 4050);
FORCEPROP 2 LAST CDS_LIB mstr_symbols
J 0
(-6575 4050);
PAINT ORANGE (-6575 4050);
DISPLAY INVISIBLE (-6575 4050);
FORCEPROP 1 LAST COMMENT_BODY TRUE
J 0
(-6550 4150);
DISPLAY 0.978723 (-6550 4150);
PAINT ORANGE (-6550 4150);
DISPLAY INVISIBLE (-6550 4150);
FORCEADD DESIGN_NOTE..1
(-6075 2600);
FORCEPROP 1 LAST COMMENT_BODY TRUE
J 0
(-6050 2700);
DISPLAY 0.978723 (-6050 2700);
PAINT ORANGE (-6050 2700);
DISPLAY INVISIBLE (-6050 2700);
FORCEPROP 2 LAST CDS_LIB mstr_symbols
J 0
(-6075 2600);
PAINT ORANGE (-6075 2600);
DISPLAY INVISIBLE (-6075 2600);
FORCEADD DNS..2
(-4670 3170);
PAINT RED (-4670 3170);
FORCEPROP 1 LAST COMMENT_BODY TRUE
R 1
J 0
(-4595 2945);
DISPLAY 0.872340 (-4595 2945);
PAINT GREEN (-4595 2945);
DISPLAY INVISIBLE (-4595 2945);
FORCEPROP 2 LAST CDS_LIB mstr_misc
J 0
(-4670 3170);
PAINT ORANGE (-4670 3170);
DISPLAY INVISIBLE (-4670 3170);
FORCEADD CAD_NOTE..1
(-7175 800);
FORCEPROP 0 LAST L1 PLEASE CONTACT DE WHEN CONNECTING THESE RESISTORS
J 0
(-7325 675);
DISPLAY 0.808511 (-7325 675);
PAINT ORANGE (-7325 675);
FORCEPROP 2 LAST CDS_LIB mstr_symbols
J 0
(-7175 800);
PAINT MONO (-7175 800);
DISPLAY INVISIBLE (-7175 800);
FORCEPROP 1 LAST COMMENT_BODY TRUE
J 0
(-7150 900);
DISPLAY 0.978723 (-7150 900);
PAINT ORANGE (-7150 900);
DISPLAY INVISIBLE (-7150 900);
FORCEADD DNS..2
(-4845 4620);
PAINT RED (-4845 4620);
FORCEPROP 1 LAST COMMENT_BODY TRUE
R 1
J 0
(-4770 4395);
DISPLAY 0.872340 (-4770 4395);
PAINT GREEN (-4770 4395);
DISPLAY INVISIBLE (-4770 4395);
FORCEPROP 2 LAST CDS_LIB mstr_misc
J 0
(-4845 4620);
PAINT ORANGE (-4845 4620);
DISPLAY INVISIBLE (-4845 4620);
FORCEADD CAD_NOTE..1
(-825 2250);
FORCEPROP 0 LAST L1 PLACE CAP CLOSE
J 0
(-975 2125);
DISPLAY 1.021277 (-975 2125);
PAINT ORANGE (-975 2125);
FORCEPROP 0 LAST L2 TO AT24C64
J 0
(-975 2050);
DISPLAY 1.021277 (-975 2050);
PAINT ORANGE (-975 2050);
FORCEPROP 1 LAST COMMENT_BODY TRUE
J 0
(-800 2350);
DISPLAY 0.978723 (-800 2350);
PAINT ORANGE (-800 2350);
DISPLAY INVISIBLE (-800 2350);
FORCEPROP 2 LAST CDS_LIB mstr_symbols
J 0
(-825 2250);
PAINT ORANGE (-825 2250);
DISPLAY INVISIBLE (-825 2250);
FORCEADD INTEL_CORP_BPAGE..1
(-225 325);
FORCEPROP 1 LAST CDS_CON_LAST_MODIFIED Tue Dec 01 11:52:11 2015
J 0
(-1650 650);
DISPLAY 1.361702 (-1650 650);
PAINT GREEN (-1650 650);
DISPLAY INVISIBLE (-1650 650);
FORCEPROP 1 LAST CUSTOM_TXT_CDS <CURRENT_DESIGN_SHEET> OF <TOTAL_DESIGN_SHEETS>
J 0
(-725 350);
PAINT GREEN (-725 350);
FORCEPROP 2 LAST CUSTOM_TXT_CDS <XR_PAGE_TITLE>
J 0
(-8115 5575);
DISPLAY 0.638298 (-8115 5575);
PAINT PINK (-8115 5575);
DISPLAY INVISIBLE (-8115 5575);
FORCEPROP 2 LAST CUSTOM_TXT_CDS <CON_LAST_MODIFIED>
J 0
(-2150 675);
DISPLAY 1.361702 (-2150 675);
PAINT GREEN (-2150 675);
FORCEPROP 1 LAST SCH_TITLE TEMPERATURE SENSORS AND FRU
J 0
(-8175 375);
DISPLAY 1.212766 (-8175 375);
PAINT ORANGE (-8175 375);
FORCEPROP 1 LAST SCH_ADDRESS1 2200 Mission College Blvd.
J 0
(-4200 450);
DISPLAY 0.617021 (-4200 450);
PAINT GREEN (-4200 450);
FORCEPROP 1 LAST SCH_ADDRESS2 P.O. BOX 58119
J 0
(-4200 400);
DISPLAY 0.617021 (-4200 400);
PAINT GREEN (-4200 400);
FORCEPROP 1 LAST SCH_ADDRESS3 Santa Clara, CA 95052-8119
J 0
(-4200 350);
DISPLAY 0.617021 (-4200 350);
PAINT GREEN (-4200 350);
FORCEPROP 1 LAST SCH_NUMBER H4694802
J 0
(-1525 475);
DISPLAY 1.212766 (-1525 475);
PAINT YELLOW (-1525 475);
FORCEPROP 1 LAST SCH_DEPT BESD
J 1
(-4675 425);
DISPLAY 1.212766 (-4675 425);
PAINT YELLOW (-4675 425);
FORCEPROP 1 LAST SCH_REV 2.420
J 0
(-475 475);
DISPLAY 0.978723 (-475 475);
PAINT YELLOW (-475 475);
FORCEPROP 2 LAST PAGE_BORDER TRUE
J 0
(-8115 5575);
DISPLAY 0.851064 (-8115 5575);
PAINT PINK (-8115 5575);
DISPLAY INVISIBLE (-8115 5575);
FORCEPROP 1 LAST COMMENT_BODY TRUE
J 0
(-213 337);
DISPLAY 0.617021 (-213 337);
PAINT GREEN (-213 337);
DISPLAY INVISIBLE (-213 337);
FORCEPROP 2 LAST CDS_LIB mstr_symbols
J 0
(-225 325);
DISPLAY 1.361702 (-225 325);
PAINT ORANGE (-225 325);
DISPLAY INVISIBLE (-225 325);
FORCEPROP 2 LAST CDS_XR_PAGE_TITLE CR-167 : @BASEBOARD_FAB2_LIB.BASEBOARD_FAB2(SCH_1):PAGE167
J 0
(-8115 5575);
DISPLAY 0.638298 (-8115 5575);
PAINT PINK (-8115 5575);
DISPLAY INVISIBLE (-8115 5575);
WIRE 16 -1 (-4775 3900)(-4775 3975);
WIRE 16 -1 (-4350 5100)(-4350 4600);
WIRE 16 -1 (-4350 4600)(-4300 4600);
WIRE 16 -1 (-3400 4250)(-3700 4250);
WIRE 16 -1 (-3400 3900)(-3400 4250);
WIRE 16 -1 (-3225 2800)(-3525 2800);
WIRE 16 -1 (-3225 2450)(-3225 2800);
WIRE 16 -1 (-4175 3650)(-4175 3150);
WIRE 16 -1 (-4175 3150)(-4125 3150);
WIRE 16 -1 (-6400 2850)(-5150 2850);
WIRE 16 -1 (-6400 2900)(-6400 2850);
WIRE 16 -1 (-6400 2900)(-4750 2900);
WIRE 16 -1 (-6400 3025)(-6400 2900);
WIRE 16 -1 (-7700 3400)(-7700 3575);
WIRE 16 -1 (-1425 2050)(-1425 1875);
WIRE 16 -1 (-7700 4150)(-7700 4250);
WIRE 16 -1 (-3500 1100)(-3500 1200);
WIRE 16 -1 (-3075 1700)(-3000 1700);
WIRE 16 -1 (-3075 1700)(-3075 1650);
WIRE 16 -1 (-3075 1650)(-3000 1650);
WIRE 16 -1 (-3075 1100)(-3075 1650);
WIRE 16 -1 (-7700 4600)(-7700 4450);
WIRE 16 -1 (-7700 3900)(-7700 3775);
WIRE 16 -1 (-3350 2150)(-3350 2075);
WIRE 16 -1 (-5550 4350)(-6250 4350);
WIRE 16 -1 (-6250 4400)(-6250 4350);
WIRE 16 -1 (-1425 2350)(-1425 2250);
WIRE 16 -1 (-6075 2050)(-6075 2150);
WIRE 16 -1 (-6425 2050)(-6425 2150);
WIRE 16 -1 (-2550 4450)(-2050 4450);
WIRE 16 -1 (-2050 4450)(-1525 4450);
WIRE 16 -1 (-2050 3000)(-2050 4450);
FORCEPROP 2 LAST SIG_NAME SMB_SENSOR_STBY_LVC3_SCL
J 0
(-2060 4460);
DISPLAY 0.617021 (-2060 4460);
PAINT ORANGE (-2060 4460);
WIRE 16 -1 (-2200 3000)(-2050 3000);
WIRE 16 -1 (-2850 4500)(-2100 4500);
WIRE 16 -1 (-2100 4500)(-1525 4500);
FORCEPROP 2 LAST SIG_NAME SMB_SENSOR_STBY_LVC3_SDA
J 0
(-2060 4510);
DISPLAY 0.617021 (-2060 4510);
PAINT ORANGE (-2060 4510);
WIRE 16 -1 (-2100 3050)(-2100 4500);
WIRE 16 -1 (-2525 3050)(-2100 3050);
WIRE 16 -1 (-3700 4500)(-3050 4500);
FORCEPROP 2 LAST SIG_NAME SMB_SENSOR_TMP421_1_SDA
J 0
(-3610 4510);
DISPLAY 0.617021 (-3610 4510);
PAINT ORANGE (-3610 4510);
FORCEPROP 2 LASTPROP $XRERR UNIQUE?
J 0
(-3850 4510);
DISPLAY 0.638298 (-3850 4510);
PAINT MONO (-3850 4510);
DISPLAY INVISIBLE (-3850 4510);
WIRE 16 -1 (-3700 4450)(-2750 4450);
FORCEPROP 2 LAST SIG_NAME SMB_SENSOR_TMP421_1_SCL
J 0
(-3610 4460);
DISPLAY 0.617021 (-3610 4460);
PAINT ORANGE (-3610 4460);
FORCEPROP 2 LASTPROP $XRERR UNIQUE?
J 0
(-3850 4460);
DISPLAY 0.638298 (-3850 4460);
PAINT MONO (-3850 4460);
DISPLAY INVISIBLE (-3850 4460);
WIRE 16 -1 (-1425 1550)(-725 1550);
FORCEPROP 2 LAST SIG_NAME SMB_SENSOR_STBY_LVC3_SDA
J 0
(-1385 1560);
DISPLAY 0.617021 (-1385 1560);
PAINT ORANGE (-1385 1560);
WIRE 16 -1 (-2400 1550)(-1625 1550);
FORCEPROP 2 LAST SIG_NAME SMB_SENSOR_STBY_LVC3_SDA_R2
J 0
(-2335 1560);
DISPLAY 0.617021 (-2335 1560);
PAINT ORANGE (-2335 1560);
FORCEPROP 2 LASTPROP $XRERR UNIQUE?
J 0
(-2575 1560);
DISPLAY 0.638298 (-2575 1560);
PAINT MONO (-2575 1560);
DISPLAY INVISIBLE (-2575 1560);
WIRE 16 -1 (-3525 3050)(-2725 3050);
FORCEPROP 2 LAST SIG_NAME SMB_SENSOR_TMP421_2_SDA
J 0
(-3435 3060);
DISPLAY 0.617021 (-3435 3060);
PAINT ORANGE (-3435 3060);
FORCEPROP 2 LASTPROP $XRERR UNIQUE?
J 0
(-3675 3060);
DISPLAY 0.638298 (-3675 3060);
PAINT MONO (-3675 3060);
DISPLAY INVISIBLE (-3675 3060);
WIRE 16 -1 (-3525 3000)(-2400 3000);
FORCEPROP 2 LAST SIG_NAME SMB_SENSOR_TMP421_2_SCL
J 0
(-3435 3010);
DISPLAY 0.617021 (-3435 3010);
PAINT ORANGE (-3435 3010);
FORCEPROP 2 LASTPROP $XRERR UNIQUE?
J 0
(-3675 3010);
DISPLAY 0.638298 (-3675 3010);
PAINT MONO (-3675 3010);
DISPLAY INVISIBLE (-3675 3010);
WIRE 16 -1 (-3000 1500)(-3500 1500);
FORCEPROP 2 LAST SIG_NAME PD_FRU_WP
J 0
(-3460 1510);
DISPLAY 0.617021 (-3460 1510);
PAINT ORANGE (-3460 1510);
FORCEPROP 2 LASTPROP $XRERR UNIQUE?
J 0
(-3700 1510);
DISPLAY 0.638298 (-3700 1510);
PAINT MONO (-3700 1510);
DISPLAY INVISIBLE (-3700 1510);
WIRE 16 -1 (-3500 1500)(-3500 1400);
WIRE 16 -1 (-3875 1550)(-3000 1550);
FORCEPROP 2 LAST SIG_NAME SMB_SENSOR_STBY_LVC3_SCL_R2
J 0
(-3760 1560);
DISPLAY 0.617021 (-3760 1560);
PAINT ORANGE (-3760 1560);
FORCEPROP 2 LASTPROP $XRERR UNIQUE?
J 0
(-4000 1560);
DISPLAY 0.638298 (-4000 1560);
PAINT MONO (-4000 1560);
DISPLAY INVISIBLE (-4000 1560);
WIRE 16 -1 (-3350 1750)(-3000 1750);
FORCEPROP 2 LAST SIG_NAME PU_AT24C64_A2
J 0
(-3335 1760);
DISPLAY 0.617021 (-3335 1760);
PAINT ORANGE (-3335 1760);
FORCEPROP 2 LASTPROP $XRERR UNIQUE?
J 0
(-3575 1760);
DISPLAY 0.638298 (-3575 1760);
PAINT MONO (-3575 1760);
DISPLAY INVISIBLE (-3575 1760);
WIRE 16 -1 (-3350 1875)(-3350 1750);
WIRE 16 -1 (-4675 1550)(-4075 1550);
FORCEPROP 2 LAST SIG_NAME SMB_SENSOR_STBY_LVC3_SCL
J 0
(-4660 1560);
DISPLAY 0.617021 (-4660 1560);
PAINT ORANGE (-4660 1560);
WIRE 16 -1 (-4300 4500)(-4575 4500);
WIRE 16 -1 (-4575 4500)(-4575 4775);
WIRE 16 -1 (-4575 4775)(-4850 4775);
FORCEPROP 2 LAST SIG_NAME ISENSE_TMP421_1_DXP
J 0
(-4985 4785);
DISPLAY 0.617021 (-4985 4785);
PAINT ORANGE (-4985 4785);
FORCEPROP 2 LASTPROP $XRERR UNIQUE?
J 0
(-5225 4785);
DISPLAY 0.638298 (-5225 4785);
PAINT MONO (-5225 4785);
DISPLAY INVISIBLE (-5225 4785);
WIRE 16 -1 (-4850 4775)(-4850 4725);
WIRE 16 -1 (-4850 4775)(-5050 4775);
WIRE 16 -1 (-4775 4300)(-4300 4300);
FORCEPROP 2 LAST SIG_NAME PD_TMP421_1_A0
J 0
(-4650 4310);
DISPLAY 0.617021 (-4650 4310);
PAINT ORANGE (-4650 4310);
FORCEPROP 2 LASTPROP $XRERR UNIQUE?
J 0
(-4890 4310);
DISPLAY 0.638298 (-4890 4310);
PAINT MONO (-4890 4310);
DISPLAY INVISIBLE (-4890 4310);
WIRE 16 -1 (-4775 4175)(-4775 4300);
WIRE 16 -1 (-4300 4450)(-4850 4450);
FORCEPROP 2 LAST SIG_NAME ISENSE_TMP421_1_DXN
J 0
(-4835 4460);
DISPLAY 0.617021 (-4835 4460);
PAINT ORANGE (-4835 4460);
FORCEPROP 2 LASTPROP $XRERR UNIQUE?
J 0
(-5075 4460);
DISPLAY 0.638298 (-5075 4460);
PAINT MONO (-5075 4460);
DISPLAY INVISIBLE (-5075 4460);
WIRE 16 -1 (-4850 4525)(-4850 4450);
WIRE 16 -1 (-4850 4450)(-5050 4450);
WIRE 16 -1 (-5350 4350)(-4300 4350);
FORCEPROP 2 LAST SIG_NAME PU_TMP421_1_A1
J 0
(-4650 4360);
DISPLAY 0.617021 (-4650 4360);
PAINT ORANGE (-4650 4360);
FORCEPROP 2 LASTPROP $XRERR UNIQUE?
J 0
(-4890 4360);
DISPLAY 0.638298 (-4890 4360);
PAINT MONO (-4890 4360);
DISPLAY INVISIBLE (-4890 4360);
WIRE 16 -1 (-5675 4600)(-5325 4600);
WIRE 16 -1 (-5325 4600)(-5325 4450);
WIRE 16 -1 (-5250 4450)(-5325 4450);
WIRE 16 -1 (-5325 4450)(-5825 4450);
FORCEPROP 2 LAST SIG_NAME ISENSE_TMP421_1_BC
J 0
(-5835 4410);
DISPLAY 0.617021 (-5835 4410);
PAINT ORANGE (-5835 4410);
FORCEPROP 2 LASTPROP $XRERR UNIQUE?
J 0
(-6075 4410);
DISPLAY 0.638298 (-6075 4410);
PAINT MONO (-6075 4410);
DISPLAY INVISIBLE (-6075 4410);
WIRE 16 -1 (-5825 4500)(-5825 4450);
WIRE 16 -1 (-5825 4775)(-5250 4775);
FORCEPROP 2 LAST SIG_NAME ISENSE_TMP421_1_E
J 0
(-5810 4785);
DISPLAY 0.617021 (-5810 4785);
PAINT ORANGE (-5810 4785);
FORCEPROP 2 LASTPROP $XRERR UNIQUE?
J 0
(-6050 4785);
DISPLAY 0.638298 (-6050 4785);
PAINT MONO (-6050 4785);
DISPLAY INVISIBLE (-6050 4785);
WIRE 16 -1 (-5825 4700)(-5825 4775);
WIRE 16 -1 (-4400 3325)(-4675 3325);
WIRE 16 -1 (-4400 3050)(-4400 3325);
WIRE 16 -1 (-4675 3325)(-4675 3275);
WIRE 16 -1 (-4675 3325)(-4900 3325);
FORCEPROP 2 LAST SIG_NAME ISENSE_TMP421_2_DXP
J 0
(-4835 3335);
DISPLAY 0.617021 (-4835 3335);
PAINT ORANGE (-4835 3335);
FORCEPROP 2 LASTPROP $XRERR UNIQUE?
J 0
(-5075 3335);
DISPLAY 0.638298 (-5075 3335);
PAINT MONO (-5075 3335);
DISPLAY INVISIBLE (-5075 3335);
WIRE 16 -1 (-4125 3050)(-4400 3050);
WIRE 16 -1 (-4675 3075)(-4675 3000);
WIRE 16 -1 (-4125 3000)(-4675 3000);
FORCEPROP 2 LAST SIG_NAME ISENSE_TMP421_2_DXN
J 2
(-4175 3010);
DISPLAY 0.617021 (-4175 3010);
PAINT ORANGE (-4175 3010);
FORCEPROP 2 LASTPROP $XRERR UNIQUE?
J 0
(-4415 3010);
DISPLAY 0.638298 (-4415 3010);
PAINT MONO (-4415 3010);
DISPLAY INVISIBLE (-4415 3010);
WIRE 16 -1 (-4675 3000)(-4875 3000);
WIRE 16 -1 (-4550 2900)(-4125 2900);
FORCEPROP 2 LAST SIG_NAME PD_TMP421_2_A1
J 2
(-4175 2910);
DISPLAY 0.617021 (-4175 2910);
PAINT ORANGE (-4175 2910);
FORCEPROP 2 LASTPROP $XRERR UNIQUE?
J 0
(-4415 2910);
DISPLAY 0.638298 (-4415 2910);
PAINT MONO (-4415 2910);
DISPLAY INVISIBLE (-4415 2910);
WIRE 16 -1 (-4950 2850)(-4125 2850);
FORCEPROP 2 LAST SIG_NAME PU_TMP421_2_A0
J 2
(-4175 2860);
DISPLAY 0.617021 (-4175 2860);
PAINT ORANGE (-4175 2860);
FORCEPROP 2 LASTPROP $XRERR UNIQUE?
J 0
(-4415 2860);
DISPLAY 0.638298 (-4415 2860);
PAINT MONO (-4415 2860);
DISPLAY INVISIBLE (-4415 2860);
WIRE 16 -1 (-5750 3050)(-5750 3000);
WIRE 16 -1 (-5125 3000)(-5750 3000);
FORCEPROP 2 LAST SIG_NAME ISENSE_TMP421_2_BC
J 0
(-5960 2935);
DISPLAY 0.617021 (-5960 2935);
PAINT ORANGE (-5960 2935);
FORCEPROP 2 LASTPROP $XRERR UNIQUE?
J 0
(-6200 2935);
DISPLAY 0.638298 (-6200 2935);
PAINT MONO (-6200 2935);
DISPLAY INVISIBLE (-6200 2935);
WIRE 16 -1 (-5075 3000)(-5125 3000);
WIRE 16 -1 (-5125 3150)(-5125 3000);
WIRE 16 -1 (-5600 3150)(-5125 3150);
WIRE 16 -1 (-5750 3325)(-5100 3325);
WIRE 16 -1 (-5750 3250)(-5750 3325);
FORCEPROP 2 LAST SIG_NAME ISENSE_TMP421_2_E
J 0
(-5910 3360);
DISPLAY 0.617021 (-5910 3360);
PAINT ORANGE (-5910 3360);
FORCEPROP 2 LASTPROP $XRERR UNIQUE?
J 0
(-6150 3360);
DISPLAY 0.638298 (-6150 3360);
PAINT MONO (-6150 3360);
DISPLAY INVISIBLE (-6150 3360);
WIRE 16 -1 (-6075 1850)(-6075 1325);
WIRE 16 -1 (-6075 1325)(-5800 1325);
WIRE 16 -1 (-6625 1325)(-6075 1325);
FORCEPROP 2 LAST SIG_NAME SMB_SENSOR_STBY_LVC3_SCL
J 0
(-6585 1335);
DISPLAY 0.617021 (-6585 1335);
PAINT ORANGE (-6585 1335);
WIRE 16 682 (-5875 600)(-5875 1650);
WIRE 16 682 (-7400 600)(-5875 600);
WIRE 16 682 (-5875 1650)(-7400 1650);
WIRE 16 682 (-7400 1650)(-7400 600);
WIRE 16 -1 (-6425 1850)(-6425 1450);
WIRE 16 -1 (-6425 1450)(-5800 1450);
WIRE 16 -1 (-6625 1450)(-6425 1450);
FORCEPROP 2 LAST SIG_NAME SMB_SENSOR_STBY_LVC3_SDA
J 0
(-6535 1460);
DISPLAY 0.617021 (-6535 1460);
PAINT ORANGE (-6535 1460);
WIRE 16 -1 (-6625 1150)(-5800 1150);
FORCEPROP 2 LAST SIG_NAME SMB_SENSOR_STBY_LVC3_SDA
J 0
(-6535 1160);
DISPLAY 0.617021 (-6535 1160);
PAINT ORANGE (-6535 1160);
WIRE 16 -1 (-6625 1025)(-5800 1025);
FORCEPROP 2 LAST SIG_NAME SMB_SENSOR_STBY_LVC3_SCL
J 0
(-6585 1035);
DISPLAY 0.617021 (-6585 1035);
PAINT ORANGE (-6585 1035);
WIRE 16 -1 (-7475 1450)(-6825 1450);
FORCEPROP 2 LAST SIG_NAME SMB_SENSOR_BMC_STBY_LVC3_SDA
J 0
(-7460 1460);
DISPLAY 0.617021 (-7460 1460);
PAINT ORANGE (-7460 1460);
WIRE 16 -1 (-7475 1325)(-6825 1325);
FORCEPROP 2 LAST SIG_NAME SMB_SENSOR_BMC_STBY_LVC3_SCL
J 0
(-7460 1335);
DISPLAY 0.617021 (-7460 1335);
PAINT ORANGE (-7460 1335);
WIRE 16 -1 (-7475 1150)(-6825 1150);
FORCEPROP 2 LAST SIG_NAME SMB_SENSOR_PCH_STBY_LVC3_SDA
J 0
(-7460 1160);
DISPLAY 0.617021 (-7460 1160);
PAINT ORANGE (-7460 1160);
WIRE 16 -1 (-7475 1025)(-6825 1025);
FORCEPROP 2 LAST SIG_NAME SMB_SENSOR_PCH_STBY_LVC3_SCL
J 0
(-7460 1035);
DISPLAY 0.617021 (-7460 1035);
PAINT ORANGE (-7460 1035);
DOT 1 (-6425 1450);
DOT 1 (-6400 2900);
DOT 1 (-6075 1325);
DOT 1 (-5125 3000);
DOT 1 (-4675 3000);
DOT 1 (-4675 3325);
DOT 1 (-5325 4450);
DOT 1 (-4850 4450);
DOT 1 (-4850 4775);
DOT 1 (-3075 1650);
DOT 1 (-2100 4500);
DOT 1 (-2050 4450);
FORCENOTE
ROOM=SM_THERM
(-8117 625) 0;
DISPLAY LEFT (-8117 625);
DISPLAY 0.617021 (-8117 625);
PAINT PURPLE (-8117 625);
FORCENOTE
SMBUS ADDRESS 0X9E
(-6275 2475) 0;
DISPLAY LEFT (-6275 2475);
DISPLAY 1.021277 (-6275 2475);
PAINT PURPLE (-6275 2475);
FORCENOTE
SMBUS ADDRESS 0X9C
(-6775 3925) 0;
DISPLAY LEFT (-6775 3925);
DISPLAY 1.021277 (-6775 3925);
PAINT PURPLE (-6775 3925);
FORCENOTE
SMBUS ADDRESS 0XA8
(-2300 1175) 0;
DISPLAY LEFT (-2300 1175);
DISPLAY 1.021277 (-2300 1175);
PAINT PURPLE (-2300 1175);
QUIT
